(kicad_sch
	(version 20250114)
	(generator "eeschema")
	(generator_version "9.0")
	(paper "A3")
	(title_block
		(title "OCuLink to 10GbE adapter")
		(date "2026-02-23")
		(rev "1.1.0")
		(company "Antmicro Ltd")
		(comment 1 "www.antmicro.com")
	)
	(bus_alias "10GbE"
		(members "D4+" "D4-" "D3+" "D3-" "D2+" "D2-" "D1+" "D1-")
	)
	(text "X710-AT2 10GbE Interface"
		(exclude_from_sim no)
		(at 215.9 25.4 0)
		(effects
			(font
				(size 2.54 2.54)
				(thickness 0.508)
				(bold yes)
			)
		)
	)
	(text_box "NOTE: Place these 2 resistors close to the controller."
		(exclude_from_sim no)
		(at 234.95 128.27 0)
		(size 54.61 5.08)
		(margins 0.9525 0.9525 0.9525 0.9525)
		(stroke
			(width 0)
			(type solid)
		)
		(fill
			(type none)
		)
		(effects
			(font
				(size 1.27 1.27)
			)
		)
	)
	(junction
		(at 38.1 217.17)
		(diameter 0)
		(color 0 0 0 0)
	)
	(junction
		(at 133.35 223.52)
		(diameter 0)
		(color 0 0 0 0)
	)
	(junction
		(at 261.62 228.6)
		(diameter 0)
		(color 0 0 0 0)
	)
	(junction
		(at 175.26 167.64)
		(diameter 0)
		(color 0 0 0 0)
	)
	(junction
		(at 175.26 243.84)
		(diameter 0)
		(color 0 0 0 0)
	)
	(junction
		(at 160.02 157.48)
		(diameter 0)
		(color 0 0 0 0)
	)
	(junction
		(at 137.16 157.48)
		(diameter 0)
		(color 0 0 0 0)
	)
	(junction
		(at 58.42 217.17)
		(diameter 0)
		(color 0 0 0 0)
	)
	(junction
		(at 175.26 157.48)
		(diameter 0)
		(color 0 0 0 0)
	)
	(junction
		(at 142.24 226.06)
		(diameter 0)
		(color 0 0 0 0)
	)
	(junction
		(at 167.64 157.48)
		(diameter 0)
		(color 0 0 0 0)
	)
	(junction
		(at 62.23 217.17)
		(diameter 0)
		(color 0 0 0 0)
	)
	(junction
		(at 167.64 170.18)
		(diameter 0)
		(color 0 0 0 0)
	)
	(junction
		(at 144.78 157.48)
		(diameter 0)
		(color 0 0 0 0)
	)
	(junction
		(at 152.4 157.48)
		(diameter 0)
		(color 0 0 0 0)
	)
	(junction
		(at 261.62 218.44)
		(diameter 0)
		(color 0 0 0 0)
	)
	(junction
		(at 91.44 170.18)
		(diameter 0)
		(color 0 0 0 0)
	)
	(junction
		(at 100.33 167.64)
		(diameter 0)
		(color 0 0 0 0)
	)
	(junction
		(at 129.54 157.48)
		(diameter 0)
		(color 0 0 0 0)
	)
	(junction
		(at 251.46 231.14)
		(diameter 0)
		(color 0 0 0 0)
	)
	(junction
		(at 53.34 217.17)
		(diameter 0)
		(color 0 0 0 0)
	)
	(no_connect
		(at 193.04 101.6)
	)
	(no_connect
		(at 193.04 111.76)
	)
	(no_connect
		(at 193.04 93.98)
	)
	(no_connect
		(at 238.76 213.36)
	)
	(no_connect
		(at 238.76 200.66)
	)
	(no_connect
		(at 238.76 180.34)
	)
	(no_connect
		(at 238.76 182.88)
	)
	(no_connect
		(at 193.04 218.44)
	)
	(no_connect
		(at 238.76 215.9)
	)
	(no_connect
		(at 193.04 88.9)
	)
	(no_connect
		(at 193.04 210.82)
	)
	(no_connect
		(at 238.76 187.96)
	)
	(no_connect
		(at 193.04 86.36)
	)
	(no_connect
		(at 193.04 213.36)
	)
	(no_connect
		(at 238.76 203.2)
	)
	(no_connect
		(at 238.76 198.12)
	)
	(no_connect
		(at 193.04 205.74)
	)
	(no_connect
		(at 238.76 210.82)
	)
	(no_connect
		(at 193.04 109.22)
	)
	(no_connect
		(at 193.04 104.14)
	)
	(no_connect
		(at 193.04 215.9)
	)
	(no_connect
		(at 193.04 96.52)
	)
	(no_connect
		(at 238.76 205.74)
	)
	(no_connect
		(at 238.76 218.44)
	)
	(no_connect
		(at 238.76 185.42)
	)
	(bus_entry
		(at 261.62 71.12)
		(size -2.54 -2.54)
		(stroke
			(width 0)
			(type default)
		)
	)
	(bus_entry
		(at 261.62 55.88)
		(size -2.54 -2.54)
		(stroke
			(width 0)
			(type default)
		)
	)
	(bus_entry
		(at 170.18 78.74)
		(size 2.54 -2.54)
		(stroke
			(width 0)
			(type default)
		)
	)
	(bus_entry
		(at 261.62 78.74)
		(size -2.54 -2.54)
		(stroke
			(width 0)
			(type default)
		)
	)
	(bus_entry
		(at 261.62 73.66)
		(size -2.54 -2.54)
		(stroke
			(width 0)
			(type default)
		)
	)
	(bus_entry
		(at 78.74 170.18)
		(size 2.54 -2.54)
		(stroke
			(width 0)
			(type default)
		)
	)
	(bus_entry
		(at 170.18 63.5)
		(size 2.54 -2.54)
		(stroke
			(width 0)
			(type default)
		)
	)
	(bus_entry
		(at 170.18 81.28)
		(size 2.54 -2.54)
		(stroke
			(width 0)
			(type default)
		)
	)
	(bus_entry
		(at 261.62 66.04)
		(size -2.54 -2.54)
		(stroke
			(width 0)
			(type default)
		)
	)
	(bus_entry
		(at 170.18 58.42)
		(size 2.54 -2.54)
		(stroke
			(width 0)
			(type default)
		)
	)
	(bus_entry
		(at 78.74 172.72)
		(size 2.54 -2.54)
		(stroke
			(width 0)
			(type default)
		)
	)
	(bus_entry
		(at 261.62 81.28)
		(size -2.54 -2.54)
		(stroke
			(width 0)
			(type default)
		)
	)
	(bus_entry
		(at 170.18 66.04)
		(size 2.54 -2.54)
		(stroke
			(width 0)
			(type default)
		)
	)
	(bus_entry
		(at 261.62 58.42)
		(size -2.54 -2.54)
		(stroke
			(width 0)
			(type default)
		)
	)
	(bus_entry
		(at 170.18 55.88)
		(size 2.54 -2.54)
		(stroke
			(width 0)
			(type default)
		)
	)
	(bus_entry
		(at 170.18 71.12)
		(size 2.54 -2.54)
		(stroke
			(width 0)
			(type default)
		)
	)
	(bus_entry
		(at 170.18 73.66)
		(size 2.54 -2.54)
		(stroke
			(width 0)
			(type default)
		)
	)
	(bus_entry
		(at 261.62 63.5)
		(size -2.54 -2.54)
		(stroke
			(width 0)
			(type default)
		)
	)
	(wire
		(pts
			(xy 251.46 218.44) (xy 261.62 218.44)
		)
		(stroke
			(width 0)
			(type default)
		)
	)
	(wire
		(pts
			(xy 133.35 228.6) (xy 133.35 223.52)
		)
		(stroke
			(width 0)
			(type default)
		)
	)
	(wire
		(pts
			(xy 144.78 182.88) (xy 144.78 165.1)
		)
		(stroke
			(width 0)
			(type default)
		)
	)
	(bus
		(pts
			(xy 261.62 81.28) (xy 261.62 83.82)
		)
		(stroke
			(width 0)
			(type default)
		)
	)
	(wire
		(pts
			(xy 193.04 68.58) (xy 172.72 68.58)
		)
		(stroke
			(width 0)
			(type default)
		)
	)
	(wire
		(pts
			(xy 175.26 167.64) (xy 175.26 165.1)
		)
		(stroke
			(width 0)
			(type default)
		)
	)
	(wire
		(pts
			(xy 62.23 217.17) (xy 62.23 226.06)
		)
		(stroke
			(width 0)
			(type default)
		)
	)
	(wire
		(pts
			(xy 100.33 226.06) (xy 121.92 226.06)
		)
		(stroke
			(width 0)
			(type default)
		)
	)
	(wire
		(pts
			(xy 175.26 251.46) (xy 175.26 254)
		)
		(stroke
			(width 0)
			(type default)
		)
	)
	(wire
		(pts
			(xy 193.04 55.88) (xy 172.72 55.88)
		)
		(stroke
			(width 0)
			(type default)
		)
	)
	(wire
		(pts
			(xy 193.04 60.96) (xy 172.72 60.96)
		)
		(stroke
			(width 0)
			(type default)
		)
	)
	(wire
		(pts
			(xy 121.92 165.1) (xy 121.92 193.04)
		)
		(stroke
			(width 0)
			(type default)
		)
	)
	(wire
		(pts
			(xy 261.62 228.6) (xy 261.62 233.68)
		)
		(stroke
			(width 0)
			(type default)
		)
	)
	(wire
		(pts
			(xy 100.33 167.64) (xy 100.33 175.26)
		)
		(stroke
			(width 0)
			(type default)
		)
	)
	(wire
		(pts
			(xy 91.44 170.18) (xy 105.41 170.18)
		)
		(stroke
			(width 0)
			(type default)
		)
	)
	(bus
		(pts
			(xy 78.74 172.72) (xy 78.74 175.26)
		)
		(stroke
			(width 0)
			(type default)
		)
	)
	(wire
		(pts
			(xy 142.24 233.68) (xy 142.24 236.22)
		)
		(stroke
			(width 0)
			(type default)
		)
	)
	(wire
		(pts
			(xy 78.74 217.17) (xy 62.23 217.17)
		)
		(stroke
			(width 0)
			(type default)
		)
	)
	(bus
		(pts
			(xy 261.62 73.66) (xy 261.62 78.74)
		)
		(stroke
			(width 0)
			(type default)
		)
	)
	(wire
		(pts
			(xy 121.92 193.04) (xy 193.04 193.04)
		)
		(stroke
			(width 0)
			(type default)
		)
	)
	(wire
		(pts
			(xy 238.76 55.88) (xy 259.08 55.88)
		)
		(stroke
			(width 0)
			(type default)
		)
	)
	(wire
		(pts
			(xy 53.34 217.17) (xy 58.42 217.17)
		)
		(stroke
			(width 0)
			(type default)
		)
	)
	(wire
		(pts
			(xy 58.42 214.63) (xy 58.42 217.17)
		)
		(stroke
			(width 0)
			(type default)
		)
	)
	(bus
		(pts
			(xy 167.64 86.36) (xy 165.1 86.36)
		)
		(stroke
			(width 0)
			(type default)
		)
	)
	(wire
		(pts
			(xy 238.76 109.22) (xy 264.16 109.22)
		)
		(stroke
			(width 0)
			(type default)
		)
	)
	(wire
		(pts
			(xy 142.24 226.06) (xy 142.24 228.6)
		)
		(stroke
			(width 0)
			(type default)
		)
	)
	(wire
		(pts
			(xy 114.3 200.66) (xy 153.67 200.66)
		)
		(stroke
			(width 0)
			(type default)
		)
	)
	(wire
		(pts
			(xy 238.76 228.6) (xy 261.62 228.6)
		)
		(stroke
			(width 0)
			(type default)
		)
	)
	(bus
		(pts
			(xy 261.62 55.88) (xy 261.62 58.42)
		)
		(stroke
			(width 0)
			(type default)
		)
	)
	(wire
		(pts
			(xy 261.62 226.06) (xy 261.62 228.6)
		)
		(stroke
			(width 0)
			(type default)
		)
	)
	(wire
		(pts
			(xy 238.76 63.5) (xy 259.08 63.5)
		)
		(stroke
			(width 0)
			(type default)
		)
	)
	(bus
		(pts
			(xy 170.18 66.04) (xy 170.18 71.12)
		)
		(stroke
			(width 0)
			(type default)
		)
	)
	(wire
		(pts
			(xy 114.3 203.2) (xy 153.67 203.2)
		)
		(stroke
			(width 0)
			(type default)
		)
	)
	(wire
		(pts
			(xy 193.04 78.74) (xy 172.72 78.74)
		)
		(stroke
			(width 0)
			(type default)
		)
	)
	(wire
		(pts
			(xy 121.92 157.48) (xy 121.92 160.02)
		)
		(stroke
			(width 0)
			(type default)
		)
	)
	(wire
		(pts
			(xy 238.76 111.76) (xy 255.27 111.76)
		)
		(stroke
			(width 0)
			(type default)
		)
	)
	(bus
		(pts
			(xy 264.16 86.36) (xy 261.62 83.82)
		)
		(stroke
			(width 0)
			(type default)
		)
	)
	(wire
		(pts
			(xy 238.76 60.96) (xy 259.08 60.96)
		)
		(stroke
			(width 0)
			(type default)
		)
	)
	(wire
		(pts
			(xy 238.76 172.72) (xy 252.73 172.72)
		)
		(stroke
			(width 0)
			(type default)
		)
	)
	(wire
		(pts
			(xy 251.46 226.06) (xy 251.46 231.14)
		)
		(stroke
			(width 0)
			(type default)
		)
	)
	(bus
		(pts
			(xy 167.64 86.36) (xy 170.18 83.82)
		)
		(stroke
			(width 0)
			(type default)
		)
	)
	(bus
		(pts
			(xy 170.18 81.28) (xy 170.18 83.82)
		)
		(stroke
			(width 0)
			(type default)
		)
	)
	(wire
		(pts
			(xy 193.04 63.5) (xy 172.72 63.5)
		)
		(stroke
			(width 0)
			(type default)
		)
	)
	(wire
		(pts
			(xy 91.44 170.18) (xy 91.44 175.26)
		)
		(stroke
			(width 0)
			(type default)
		)
	)
	(wire
		(pts
			(xy 78.74 223.52) (xy 78.74 217.17)
		)
		(stroke
			(width 0)
			(type default)
		)
	)
	(wire
		(pts
			(xy 261.62 218.44) (xy 261.62 220.98)
		)
		(stroke
			(width 0)
			(type default)
		)
	)
	(wire
		(pts
			(xy 251.46 238.76) (xy 251.46 241.3)
		)
		(stroke
			(width 0)
			(type default)
		)
	)
	(wire
		(pts
			(xy 255.27 119.38) (xy 255.27 121.92)
		)
		(stroke
			(width 0)
			(type default)
		)
	)
	(wire
		(pts
			(xy 152.4 160.02) (xy 152.4 157.48)
		)
		(stroke
			(width 0)
			(type default)
		)
	)
	(wire
		(pts
			(xy 160.02 157.48) (xy 152.4 157.48)
		)
		(stroke
			(width 0)
			(type default)
		)
	)
	(wire
		(pts
			(xy 81.28 228.6) (xy 78.74 228.6)
		)
		(stroke
			(width 0)
			(type default)
		)
	)
	(wire
		(pts
			(xy 238.76 175.26) (xy 252.73 175.26)
		)
		(stroke
			(width 0)
			(type default)
		)
	)
	(wire
		(pts
			(xy 261.62 215.9) (xy 261.62 218.44)
		)
		(stroke
			(width 0)
			(type default)
		)
	)
	(wire
		(pts
			(xy 175.26 167.64) (xy 193.04 167.64)
		)
		(stroke
			(width 0)
			(type default)
		)
	)
	(wire
		(pts
			(xy 48.26 217.17) (xy 53.34 217.17)
		)
		(stroke
			(width 0)
			(type default)
		)
	)
	(wire
		(pts
			(xy 78.74 228.6) (xy 78.74 236.22)
		)
		(stroke
			(width 0)
			(type default)
		)
	)
	(wire
		(pts
			(xy 127 226.06) (xy 142.24 226.06)
		)
		(stroke
			(width 0)
			(type default)
		)
	)
	(wire
		(pts
			(xy 238.76 231.14) (xy 251.46 231.14)
		)
		(stroke
			(width 0)
			(type default)
		)
	)
	(bus
		(pts
			(xy 261.62 78.74) (xy 261.62 81.28)
		)
		(stroke
			(width 0)
			(type default)
		)
	)
	(wire
		(pts
			(xy 238.76 170.18) (xy 252.73 170.18)
		)
		(stroke
			(width 0)
			(type default)
		)
	)
	(wire
		(pts
			(xy 238.76 76.2) (xy 259.08 76.2)
		)
		(stroke
			(width 0)
			(type default)
		)
	)
	(wire
		(pts
			(xy 53.34 229.87) (xy 53.34 236.22)
		)
		(stroke
			(width 0)
			(type default)
		)
	)
	(bus
		(pts
			(xy 170.18 73.66) (xy 170.18 78.74)
		)
		(stroke
			(width 0)
			(type default)
		)
	)
	(wire
		(pts
			(xy 129.54 190.5) (xy 193.04 190.5)
		)
		(stroke
			(width 0)
			(type default)
		)
	)
	(bus
		(pts
			(xy 170.18 71.12) (xy 170.18 73.66)
		)
		(stroke
			(width 0)
			(type default)
		)
	)
	(wire
		(pts
			(xy 127 223.52) (xy 133.35 223.52)
		)
		(stroke
			(width 0)
			(type default)
		)
	)
	(wire
		(pts
			(xy 110.49 167.64) (xy 175.26 167.64)
		)
		(stroke
			(width 0)
			(type default)
		)
	)
	(wire
		(pts
			(xy 152.4 177.8) (xy 152.4 165.1)
		)
		(stroke
			(width 0)
			(type default)
		)
	)
	(bus
		(pts
			(xy 170.18 55.88) (xy 170.18 58.42)
		)
		(stroke
			(width 0)
			(type default)
		)
	)
	(bus
		(pts
			(xy 261.62 66.04) (xy 261.62 71.12)
		)
		(stroke
			(width 0)
			(type default)
		)
	)
	(wire
		(pts
			(xy 167.64 165.1) (xy 167.64 170.18)
		)
		(stroke
			(width 0)
			(type default)
		)
	)
	(wire
		(pts
			(xy 152.4 157.48) (xy 144.78 157.48)
		)
		(stroke
			(width 0)
			(type default)
		)
	)
	(wire
		(pts
			(xy 251.46 231.14) (xy 251.46 233.68)
		)
		(stroke
			(width 0)
			(type default)
		)
	)
	(wire
		(pts
			(xy 81.28 167.64) (xy 100.33 167.64)
		)
		(stroke
			(width 0)
			(type default)
		)
	)
	(wire
		(pts
			(xy 81.28 226.06) (xy 69.85 226.06)
		)
		(stroke
			(width 0)
			(type default)
		)
	)
	(bus
		(pts
			(xy 261.62 63.5) (xy 261.62 66.04)
		)
		(stroke
			(width 0)
			(type default)
		)
	)
	(wire
		(pts
			(xy 175.26 243.84) (xy 181.61 243.84)
		)
		(stroke
			(width 0)
			(type default)
		)
	)
	(wire
		(pts
			(xy 160.02 175.26) (xy 193.04 175.26)
		)
		(stroke
			(width 0)
			(type default)
		)
	)
	(wire
		(pts
			(xy 264.16 119.38) (xy 264.16 121.92)
		)
		(stroke
			(width 0)
			(type default)
		)
	)
	(wire
		(pts
			(xy 129.54 157.48) (xy 129.54 160.02)
		)
		(stroke
			(width 0)
			(type default)
		)
	)
	(wire
		(pts
			(xy 133.35 223.52) (xy 163.83 223.52)
		)
		(stroke
			(width 0)
			(type default)
		)
	)
	(wire
		(pts
			(xy 38.1 217.17) (xy 43.18 217.17)
		)
		(stroke
			(width 0)
			(type default)
		)
	)
	(wire
		(pts
			(xy 261.62 238.76) (xy 261.62 241.3)
		)
		(stroke
			(width 0)
			(type default)
		)
	)
	(wire
		(pts
			(xy 38.1 214.63) (xy 38.1 217.17)
		)
		(stroke
			(width 0)
			(type default)
		)
	)
	(wire
		(pts
			(xy 91.44 180.34) (xy 91.44 182.88)
		)
		(stroke
			(width 0)
			(type default)
		)
	)
	(wire
		(pts
			(xy 160.02 175.26) (xy 160.02 165.1)
		)
		(stroke
			(width 0)
			(type default)
		)
	)
	(wire
		(pts
			(xy 175.26 154.94) (xy 175.26 157.48)
		)
		(stroke
			(width 0)
			(type default)
		)
	)
	(wire
		(pts
			(xy 175.26 157.48) (xy 167.64 157.48)
		)
		(stroke
			(width 0)
			(type default)
		)
	)
	(wire
		(pts
			(xy 238.76 78.74) (xy 259.08 78.74)
		)
		(stroke
			(width 0)
			(type default)
		)
	)
	(wire
		(pts
			(xy 238.76 167.64) (xy 252.73 167.64)
		)
		(stroke
			(width 0)
			(type default)
		)
	)
	(wire
		(pts
			(xy 238.76 53.34) (xy 259.08 53.34)
		)
		(stroke
			(width 0)
			(type default)
		)
	)
	(wire
		(pts
			(xy 142.24 226.06) (xy 153.67 226.06)
		)
		(stroke
			(width 0)
			(type default)
		)
	)
	(bus
		(pts
			(xy 261.62 71.12) (xy 261.62 73.66)
		)
		(stroke
			(width 0)
			(type default)
		)
	)
	(wire
		(pts
			(xy 100.33 223.52) (xy 121.92 223.52)
		)
		(stroke
			(width 0)
			(type default)
		)
	)
	(wire
		(pts
			(xy 81.28 223.52) (xy 78.74 223.52)
		)
		(stroke
			(width 0)
			(type default)
		)
	)
	(wire
		(pts
			(xy 175.26 160.02) (xy 175.26 157.48)
		)
		(stroke
			(width 0)
			(type default)
		)
	)
	(wire
		(pts
			(xy 167.64 170.18) (xy 193.04 170.18)
		)
		(stroke
			(width 0)
			(type default)
		)
	)
	(wire
		(pts
			(xy 158.75 203.2) (xy 193.04 203.2)
		)
		(stroke
			(width 0)
			(type default)
		)
	)
	(bus
		(pts
			(xy 264.16 86.36) (xy 266.7 86.36)
		)
		(stroke
			(width 0)
			(type default)
		)
	)
	(wire
		(pts
			(xy 175.26 241.3) (xy 175.26 243.84)
		)
		(stroke
			(width 0)
			(type default)
		)
	)
	(wire
		(pts
			(xy 137.16 157.48) (xy 129.54 157.48)
		)
		(stroke
			(width 0)
			(type default)
		)
	)
	(wire
		(pts
			(xy 129.54 165.1) (xy 129.54 190.5)
		)
		(stroke
			(width 0)
			(type default)
		)
	)
	(wire
		(pts
			(xy 264.16 109.22) (xy 264.16 114.3)
		)
		(stroke
			(width 0)
			(type default)
		)
	)
	(wire
		(pts
			(xy 100.33 167.64) (xy 105.41 167.64)
		)
		(stroke
			(width 0)
			(type default)
		)
	)
	(wire
		(pts
			(xy 144.78 182.88) (xy 193.04 182.88)
		)
		(stroke
			(width 0)
			(type default)
		)
	)
	(wire
		(pts
			(xy 251.46 218.44) (xy 251.46 220.98)
		)
		(stroke
			(width 0)
			(type default)
		)
	)
	(bus
		(pts
			(xy 170.18 58.42) (xy 170.18 63.5)
		)
		(stroke
			(width 0)
			(type default)
		)
	)
	(bus
		(pts
			(xy 261.62 58.42) (xy 261.62 63.5)
		)
		(stroke
			(width 0)
			(type default)
		)
	)
	(wire
		(pts
			(xy 81.28 170.18) (xy 91.44 170.18)
		)
		(stroke
			(width 0)
			(type default)
		)
	)
	(wire
		(pts
			(xy 133.35 236.22) (xy 133.35 233.68)
		)
		(stroke
			(width 0)
			(type default)
		)
	)
	(wire
		(pts
			(xy 158.75 200.66) (xy 193.04 200.66)
		)
		(stroke
			(width 0)
			(type default)
		)
	)
	(wire
		(pts
			(xy 193.04 76.2) (xy 172.72 76.2)
		)
		(stroke
			(width 0)
			(type default)
		)
	)
	(bus
		(pts
			(xy 170.18 63.5) (xy 170.18 66.04)
		)
		(stroke
			(width 0)
			(type default)
		)
	)
	(wire
		(pts
			(xy 238.76 71.12) (xy 259.08 71.12)
		)
		(stroke
			(width 0)
			(type default)
		)
	)
	(wire
		(pts
			(xy 193.04 71.12) (xy 172.72 71.12)
		)
		(stroke
			(width 0)
			(type default)
		)
	)
	(bus
		(pts
			(xy 78.74 170.18) (xy 78.74 172.72)
		)
		(stroke
			(width 0)
			(type default)
		)
	)
	(wire
		(pts
			(xy 64.77 226.06) (xy 62.23 226.06)
		)
		(stroke
			(width 0)
			(type default)
		)
	)
	(wire
		(pts
			(xy 58.42 217.17) (xy 62.23 217.17)
		)
		(stroke
			(width 0)
			(type default)
		)
	)
	(wire
		(pts
			(xy 158.75 198.12) (xy 193.04 198.12)
		)
		(stroke
			(width 0)
			(type default)
		)
	)
	(wire
		(pts
			(xy 137.16 185.42) (xy 137.16 165.1)
		)
		(stroke
			(width 0)
			(type default)
		)
	)
	(wire
		(pts
			(xy 160.02 157.48) (xy 160.02 160.02)
		)
		(stroke
			(width 0)
			(type default)
		)
	)
	(wire
		(pts
			(xy 38.1 229.87) (xy 38.1 236.22)
		)
		(stroke
			(width 0)
			(type default)
		)
	)
	(wire
		(pts
			(xy 167.64 157.48) (xy 160.02 157.48)
		)
		(stroke
			(width 0)
			(type default)
		)
	)
	(wire
		(pts
			(xy 167.64 157.48) (xy 167.64 160.02)
		)
		(stroke
			(width 0)
			(type default)
		)
	)
	(wire
		(pts
			(xy 181.61 243.84) (xy 181.61 231.14)
		)
		(stroke
			(width 0)
			(type default)
		)
	)
	(bus
		(pts
			(xy 76.2 177.8) (xy 78.74 175.26)
		)
		(stroke
			(width 0)
			(type default)
		)
	)
	(wire
		(pts
			(xy 110.49 170.18) (xy 167.64 170.18)
		)
		(stroke
			(width 0)
			(type default)
		)
	)
	(wire
		(pts
			(xy 38.1 224.79) (xy 38.1 217.17)
		)
		(stroke
			(width 0)
			(type default)
		)
	)
	(wire
		(pts
			(xy 137.16 185.42) (xy 193.04 185.42)
		)
		(stroke
			(width 0)
			(type default)
		)
	)
	(wire
		(pts
			(xy 168.91 223.52) (xy 193.04 223.52)
		)
		(stroke
			(width 0)
			(type default)
		)
	)
	(wire
		(pts
			(xy 255.27 111.76) (xy 255.27 114.3)
		)
		(stroke
			(width 0)
			(type default)
		)
	)
	(wire
		(pts
			(xy 114.3 198.12) (xy 153.67 198.12)
		)
		(stroke
			(width 0)
			(type default)
		)
	)
	(wire
		(pts
			(xy 152.4 177.8) (xy 193.04 177.8)
		)
		(stroke
			(width 0)
			(type default)
		)
	)
	(wire
		(pts
			(xy 144.78 157.48) (xy 137.16 157.48)
		)
		(stroke
			(width 0)
			(type default)
		)
	)
	(wire
		(pts
			(xy 238.76 68.58) (xy 259.08 68.58)
		)
		(stroke
			(width 0)
			(type default)
		)
	)
	(wire
		(pts
			(xy 181.61 231.14) (xy 193.04 231.14)
		)
		(stroke
			(width 0)
			(type default)
		)
	)
	(bus
		(pts
			(xy 170.18 78.74) (xy 170.18 81.28)
		)
		(stroke
			(width 0)
			(type default)
		)
	)
	(wire
		(pts
			(xy 193.04 53.34) (xy 172.72 53.34)
		)
		(stroke
			(width 0)
			(type default)
		)
	)
	(wire
		(pts
			(xy 137.16 157.48) (xy 137.16 160.02)
		)
		(stroke
			(width 0)
			(type default)
		)
	)
	(bus
		(pts
			(xy 73.66 177.8) (xy 76.2 177.8)
		)
		(stroke
			(width 0)
			(type default)
		)
	)
	(wire
		(pts
			(xy 144.78 160.02) (xy 144.78 157.48)
		)
		(stroke
			(width 0)
			(type default)
		)
	)
	(wire
		(pts
			(xy 158.75 226.06) (xy 193.04 226.06)
		)
		(stroke
			(width 0)
			(type default)
		)
	)
	(wire
		(pts
			(xy 100.33 180.34) (xy 100.33 182.88)
		)
		(stroke
			(width 0)
			(type default)
		)
	)
	(wire
		(pts
			(xy 175.26 233.68) (xy 175.26 236.22)
		)
		(stroke
			(width 0)
			(type default)
		)
	)
	(wire
		(pts
			(xy 175.26 243.84) (xy 175.26 246.38)
		)
		(stroke
			(width 0)
			(type default)
		)
	)
	(wire
		(pts
			(xy 53.34 217.17) (xy 53.34 224.79)
		)
		(stroke
			(width 0)
			(type default)
		)
	)
	(wire
		(pts
			(xy 129.54 157.48) (xy 121.92 157.48)
		)
		(stroke
			(width 0)
			(type default)
		)
	)
	(table
		(column_count 2)
		(border
			(external yes)
			(header yes)
			(stroke
				(width 0)
				(type solid)
			)
		)
		(separators
			(rows yes)
			(cols yes)
			(stroke
				(width 0)
				(type solid)
			)
		)
		(column_widths 41.91 41.91)
		(row_heights 5.08 3.81 2.54 2.54 3.81 2.54 2.54)
		(cells
			(table_cell "BASE-T PHY MDI Pair Swap Configuration\n"
				(exclude_from_sim no)
				(at 276.86 218.44 0)
				(size 83.82 5.08)
				(margins 0.9525 0.9525 0.9525 0.9525)
				(span 2 1)
				(fill
					(type none)
				)
				(effects
					(font
						(size 1.27 1.27)
						(thickness 0.254)
						(bold yes)
					)
				)
			)
			(table_cell "rgb(135, 135, 135)"
				(exclude_from_sim no)
				(at 318.77 218.44 0)
				(size 41.91 5.08)
				(margins 0.9525 0.9525 0.9525 0.9525)
				(span 0 0)
				(fill
					(type none)
				)
				(effects
					(font
						(size 1.27 1.27)
					)
					(justify left top)
				)
			)
			(table_cell "Port 0"
				(exclude_from_sim no)
				(at 276.86 223.52 0)
				(size 83.82 3.81)
				(margins 0.9525 0.9525 0.9525 0.9525)
				(span 2 1)
				(fill
					(type none)
				)
				(effects
					(font
						(size 1.27 1.27)
					)
				)
			)
			(table_cell "rgb(135, 135, 135)"
				(exclude_from_sim no)
				(at 318.77 223.52 0)
				(size 41.91 3.81)
				(margins 0.9525 0.9525 0.9525 0.9525)
				(span 0 0)
				(fill
					(type none)
				)
				(effects
					(font
						(size 1.27 1.27)
					)
					(justify left top)
				)
			)
			(table_cell "TPIN_5 = 0 (Pull down to GND with 0R) "
				(exclude_from_sim no)
				(at 276.86 227.33 0)
				(size 41.91 2.54)
				(margins 0.9525 0.9525 0.9525 0.9525)
				(span 1 1)
				(fill
					(type none)
				)
				(effects
					(font
						(size 1.27 1.27)
					)
				)
			)
			(table_cell "MDI pair swap"
				(exclude_from_sim no)
				(at 318.77 227.33 0)
				(size 41.91 2.54)
				(margins 0.9525 0.9525 0.9525 0.9525)
				(span 1 1)
				(fill
					(type none)
				)
				(effects
					(font
						(size 1.27 1.27)
					)
				)
			)
			(table_cell "TPIN_5 = 1 (Pull up to 1V88 with 1k) "
				(exclude_from_sim no)
				(at 276.86 229.87 0)
				(size 41.91 2.54)
				(margins 0.9525 0.9525 0.9525 0.9525)
				(span 1 1)
				(fill
					(type none)
				)
				(effects
					(font
						(size 1.27 1.27)
					)
				)
			)
			(table_cell "No MDI pair swap"
				(exclude_from_sim no)
				(at 318.77 229.87 0)
				(size 41.91 2.54)
				(margins 0.9525 0.9525 0.9525 0.9525)
				(span 1 1)
				(fill
					(type none)
				)
				(effects
					(font
						(size 1.27 1.27)
					)
				)
			)
			(table_cell "Port 1"
				(exclude_from_sim no)
				(at 276.86 232.41 0)
				(size 83.82 3.81)
				(margins 0.9525 0.9525 0.9525 0.9525)
				(span 2 1)
				(fill
					(type none)
				)
				(effects
					(font
						(size 1.27 1.27)
					)
				)
			)
			(table_cell "rgb(135, 135, 135)"
				(exclude_from_sim no)
				(at 318.77 232.41 0)
				(size 41.91 3.81)
				(margins 0.9525 0.9525 0.9525 0.9525)
				(span 0 0)
				(fill
					(type none)
				)
				(effects
					(font
						(size 1.27 1.27)
					)
					(justify left top)
				)
			)
			(table_cell "TPIN_3 = 0 (Pull down to GND with 0R) "
				(exclude_from_sim no)
				(at 276.86 236.22 0)
				(size 41.91 2.54)
				(margins 0.9525 0.9525 0.9525 0.9525)
				(span 1 1)
				(fill
					(type none)
				)
				(effects
					(font
						(size 1.27 1.27)
					)
				)
			)
			(table_cell "No MDI pair swap"
				(exclude_from_sim no)
				(at 318.77 236.22 0)
				(size 41.91 2.54)
				(margins 0.9525 0.9525 0.9525 0.9525)
				(span 1 1)
				(fill
					(type none)
				)
				(effects
					(font
						(size 1.27 1.27)
					)
				)
			)
			(table_cell "TPIN_3 = 1 (Pull up to 1V88 with 1k) "
				(exclude_from_sim no)
				(at 276.86 238.76 0)
				(size 41.91 2.54)
				(margins 0.9525 0.9525 0.9525 0.9525)
				(span 1 1)
				(fill
					(type none)
				)
				(effects
					(font
						(size 1.27 1.27)
					)
				)
			)
			(table_cell "MDI pair swap"
				(exclude_from_sim no)
				(at 318.77 238.76 0)
				(size 41.91 2.54)
				(margins 0.9525 0.9525 0.9525 0.9525)
				(span 1 1)
				(fill
					(type none)
				)
				(effects
					(font
						(size 1.27 1.27)
					)
				)
			)
		)
	)
	(label "MDC1_SCL1"
		(at 190.5 177.8 180)
		(effects
			(font
				(size 1.27 1.27)
			)
			(justify right bottom)
		)
	)
	(label "MDIO0_I2C0.MDIO"
		(at 82.55 167.64 0)
		(effects
			(font
				(size 1.27 1.27)
			)
			(justify left bottom)
		)
	)
	(label "~{P1_INT_R}"
		(at 190.5 203.2 180)
		(effects
			(font
				(size 1.27 1.27)
			)
			(justify right bottom)
		)
	)
	(label "TPIN_5"
		(at 241.3 228.6 0)
		(effects
			(font
				(size 1.27 1.27)
			)
			(justify left bottom)
		)
	)
	(label "Ethernet_P1.D2+"
		(at 241.3 60.96 0)
		(effects
			(font
				(size 1.27 1.27)
			)
			(justify left bottom)
		)
	)
	(label "25MHZ_OSC_AC.+"
		(at 151.13 223.52 180)
		(effects
			(font
				(size 1.27 1.27)
			)
			(justify right bottom)
		)
	)
	(label "BIAS_RDAC"
		(at 241.3 109.22 0)
		(effects
			(font
				(size 1.27 1.27)
			)
			(justify left bottom)
		)
	)
	(label "Ethernet_P0.D2+"
		(at 190.5 60.96 180)
		(effects
			(font
				(size 1.27 1.27)
			)
			(justify right bottom)
		)
	)
	(label "MDIO1_SDA1"
		(at 190.5 175.26 180)
		(effects
			(font
				(size 1.27 1.27)
			)
			(justify right bottom)
		)
	)
	(label "Ethernet_P0.D3-"
		(at 190.5 71.12 180)
		(effects
			(font
				(size 1.27 1.27)
			)
			(justify right bottom)
		)
	)
	(label "TPIN_3"
		(at 241.3 231.14 0)
		(effects
			(font
				(size 1.27 1.27)
			)
			(justify left bottom)
		)
	)
	(label "Ethernet_P0.D1+"
		(at 190.5 53.34 180)
		(effects
			(font
				(size 1.27 1.27)
			)
			(justify right bottom)
		)
	)
	(label "25MHZ_OSC_R.-"
		(at 116.84 226.06 180)
		(effects
			(font
				(size 1.27 1.27)
			)
			(justify right bottom)
		)
	)
	(label "Ethernet_P1.D4-"
		(at 241.3 78.74 0)
		(effects
			(font
				(size 1.27 1.27)
			)
			(justify left bottom)
		)
	)
	(label "Ethernet_P1.D1-"
		(at 241.3 55.88 0)
		(effects
			(font
				(size 1.27 1.27)
			)
			(justify left bottom)
		)
	)
	(label "25MHZ_OSC_R.+"
		(at 116.84 223.52 180)
		(effects
			(font
				(size 1.27 1.27)
			)
			(justify right bottom)
		)
	)
	(label "Ethernet_P0.D1-"
		(at 190.5 55.88 180)
		(effects
			(font
				(size 1.27 1.27)
			)
			(justify right bottom)
		)
	)
	(label "Ethernet_P1.D3+"
		(at 241.3 68.58 0)
		(effects
			(font
				(size 1.27 1.27)
			)
			(justify left bottom)
		)
	)
	(label "3V3_OSC"
		(at 78.74 217.17 180)
		(effects
			(font
				(size 1.27 1.27)
			)
			(justify right bottom)
		)
	)
	(label "OSC_SEL"
		(at 190.5 231.14 180)
		(effects
			(font
				(size 1.27 1.27)
			)
			(justify right bottom)
		)
	)
	(label "Ethernet_P0.D2-"
		(at 190.5 63.5 180)
		(effects
			(font
				(size 1.27 1.27)
			)
			(justify right bottom)
		)
	)
	(label "MDC3_SCL3"
		(at 190.5 193.04 180)
		(effects
			(font
				(size 1.27 1.27)
			)
			(justify right bottom)
		)
	)
	(label "Ethernet_P1.D2-"
		(at 241.3 63.5 0)
		(effects
			(font
				(size 1.27 1.27)
			)
			(justify left bottom)
		)
	)
	(label "25MHZ_OSC.+"
		(at 190.5 223.52 180)
		(effects
			(font
				(size 1.27 1.27)
			)
			(justify right bottom)
		)
	)
	(label "Ethernet_P1.D1+"
		(at 241.3 53.34 0)
		(effects
			(font
				(size 1.27 1.27)
			)
			(justify left bottom)
		)
	)
	(label "Ethernet_P0.D3+"
		(at 190.5 68.58 180)
		(effects
			(font
				(size 1.27 1.27)
			)
			(justify right bottom)
		)
	)
	(label "MDC2_SCL2"
		(at 190.5 185.42 180)
		(effects
			(font
				(size 1.27 1.27)
			)
			(justify right bottom)
		)
	)
	(label "MDIO2_SDA2"
		(at 190.5 182.88 180)
		(effects
			(font
				(size 1.27 1.27)
			)
			(justify right bottom)
		)
	)
	(label "Ethernet_P0.D4+"
		(at 190.5 76.2 180)
		(effects
			(font
				(size 1.27 1.27)
			)
			(justify right bottom)
		)
	)
	(label "MDIO3_SDA3"
		(at 190.5 190.5 180)
		(effects
			(font
				(size 1.27 1.27)
			)
			(justify right bottom)
		)
	)
	(label "MDC0_SCL0"
		(at 190.5 170.18 180)
		(effects
			(font
				(size 1.27 1.27)
			)
			(justify right bottom)
		)
	)
	(label "~{PHY_RESET_3V3_R}"
		(at 190.5 198.12 180)
		(effects
			(font
				(size 1.27 1.27)
			)
			(justify right bottom)
		)
	)
	(label "Ethernet_P0.D4-"
		(at 190.5 78.74 180)
		(effects
			(font
				(size 1.27 1.27)
			)
			(justify right bottom)
		)
	)
	(label "~{P0_INT_R}"
		(at 190.5 200.66 180)
		(effects
			(font
				(size 1.27 1.27)
			)
			(justify right bottom)
		)
	)
	(label "Ethernet_P1.D3-"
		(at 241.3 71.12 0)
		(effects
			(font
				(size 1.27 1.27)
			)
			(justify left bottom)
		)
	)
	(label "EN_OSC"
		(at 78.74 226.06 180)
		(effects
			(font
				(size 1.27 1.27)
			)
			(justify right bottom)
		)
	)
	(label "25MHZ_OSC_AC.-"
		(at 151.13 226.06 180)
		(effects
			(font
				(size 1.27 1.27)
			)
			(justify right bottom)
		)
	)
	(label "Ethernet_P1.D4+"
		(at 241.3 76.2 0)
		(effects
			(font
				(size 1.27 1.27)
			)
			(justify left bottom)
		)
	)
	(label "MDIO0_I2C0.MDC"
		(at 82.55 170.18 0)
		(effects
			(font
				(size 1.27 1.27)
			)
			(justify left bottom)
		)
	)
	(label "25MHZ_OSC.-"
		(at 190.5 226.06 180)
		(effects
			(font
				(size 1.27 1.27)
			)
			(justify right bottom)
		)
	)
	(label "MDIO0_SDA0"
		(at 190.5 167.64 180)
		(effects
			(font
				(size 1.27 1.27)
			)
			(justify right bottom)
		)
	)
	(label "RESCAL_RES_P"
		(at 241.3 111.76 0)
		(effects
			(font
				(size 1.27 1.27)
			)
			(justify left bottom)
		)
	)
	(hierarchical_label "~{P0_LED_ACT}"
		(shape output)
		(at 252.73 167.64 0)
		(effects
			(font
				(size 1.27 1.27)
			)
			(justify left)
		)
	)
	(hierarchical_label "~{P1_INT}"
		(shape input)
		(at 114.3 203.2 180)
		(effects
			(font
				(size 1.27 1.27)
			)
			(justify right)
		)
	)
	(hierarchical_label "~{PHY_RESET_3V3}"
		(shape output)
		(at 114.3 198.12 180)
		(effects
			(font
				(size 1.27 1.27)
			)
			(justify right)
		)
	)
	(hierarchical_label "Ethernet_P0{10GbE}"
		(shape bidirectional)
		(at 165.1 86.36 180)
		(effects
			(font
				(size 1.27 1.27)
			)
			(justify right)
		)
	)
	(hierarchical_label "MDIO0_I2C0{MDIO}"
		(shape bidirectional)
		(at 73.66 177.8 180)
		(effects
			(font
				(size 1.27 1.27)
			)
			(justify right)
		)
	)
	(hierarchical_label "~{P0_INT}"
		(shape input)
		(at 114.3 200.66 180)
		(effects
			(font
				(size 1.27 1.27)
			)
			(justify right)
		)
	)
	(hierarchical_label "~{P1_LED_LINK_10G}"
		(shape output)
		(at 252.73 175.26 0)
		(effects
			(font
				(size 1.27 1.27)
			)
			(justify left)
		)
	)
	(hierarchical_label "~{P0_LED_LINK_10G}"
		(shape output)
		(at 252.73 170.18 0)
		(effects
			(font
				(size 1.27 1.27)
			)
			(justify left)
		)
	)
	(hierarchical_label "~{P1_LED_ACT}"
		(shape output)
		(at 252.73 172.72 0)
		(effects
			(font
				(size 1.27 1.27)
			)
			(justify left)
		)
	)
	(hierarchical_label "Ethernet_P1{10GbE}"
		(shape bidirectional)
		(at 266.7 86.36 0)
		(effects
			(font
				(size 1.27 1.27)
			)
			(justify left)
		)
	)
	(rule_area
		(polyline
			(pts
				(xy 288.29 49.53) (xy 240.03 49.53) (xy 240.03 88.9) (xy 288.29 88.9)
			)
			(stroke
				(width 0)
				(type dash)
			)
			(fill
				(type none)
			)
		)
	)
	(rule_area
		(polyline
			(pts
				(xy 191.77 49.53) (xy 143.51 49.53) (xy 143.51 88.9) (xy 191.77 88.9)
			)
			(stroke
				(width 0)
				(type dash)
			)
			(fill
				(type none)
			)
		)
	)
	(rule_area
		(polyline
			(pts
				(xy 173.99 228.6) (xy 173.99 219.71) (xy 100.33 219.71) (xy 100.33 228.6)
			)
			(stroke
				(width 0)
				(type dash)
			)
			(fill
				(type none)
			)
		)
	)
	(netclass_flag ""
		(length 2.54)
		(shape round)
		(at 288.29 49.53 0)
		(fields_autoplaced yes)
		(effects
			(font
				(size 1.27 1.27)
			)
			(justify left bottom)
		)
		(property "Netclass" "100Ohm-diff_10GbE"
			(at 287.5915 46.99 0)
			(effects
				(font
					(size 1.27 1.27)
				)
				(justify right)
			)
		)
		(property "Component Class" ""
			(at 511.81 -3.81 0)
			(effects
				(font
					(size 1.27 1.27)
					(italic yes)
				)
				(justify left)
			)
		)
	)
	(netclass_flag ""
		(length 2.54)
		(shape round)
		(at 173.99 219.71 0)
		(fields_autoplaced yes)
		(effects
			(font
				(size 1.27 1.27)
			)
			(justify left bottom)
		)
		(property "Netclass" "100Ohm-diff_CLK"
			(at 173.2915 217.17 0)
			(effects
				(font
					(size 1.27 1.27)
				)
				(justify right)
			)
		)
		(property "Component Class" ""
			(at -50.8 7.62 0)
			(effects
				(font
					(size 1.27 1.27)
					(italic yes)
				)
				(justify right)
			)
		)
	)
	(netclass_flag ""
		(length 2.54)
		(shape round)
		(at 143.51 49.53 0)
		(fields_autoplaced yes)
		(effects
			(font
				(size 1.27 1.27)
			)
			(justify left bottom)
		)
		(property "Netclass" "100Ohm-diff_10GbE"
			(at 144.2085 46.99 0)
			(effects
				(font
					(size 1.27 1.27)
				)
				(justify left)
			)
		)
		(property "Component Class" ""
			(at -80.01 -3.81 0)
			(effects
				(font
					(size 1.27 1.27)
					(italic yes)
				)
				(justify right)
			)
		)
	)
	(symbol
		(lib_id "antmicropower:GND")
		(at 264.16 121.92 0)
		(unit 1)
		(exclude_from_sim no)
		(in_bom yes)
		(on_board yes)
		(dnp no)
		(property "Reference" "#PWR0251"
			(at 273.05 124.46 0)
			(effects
				(font
					(size 1.27 1.27)
					(thickness 0.15)
				)
				(justify left bottom)
				(hide yes)
			)
		)
		(property "Value" "GND"
			(at 264.16 125.73 0)
			(effects
				(font
					(size 1.27 1.27)
					(thickness 0.15)
				)
			)
		)
		(property "Footprint" ""
			(at 273.05 129.54 0)
			(effects
				(font
					(size 1.27 1.27)
					(thickness 0.15)
				)
				(justify left bottom)
				(hide yes)
			)
		)
		(property "Datasheet" ""
			(at 273.05 134.62 0)
			(effects
				(font
					(size 1.27 1.27)
					(thickness 0.15)
				)
				(justify left bottom)
				(hide yes)
			)
		)
		(property "Description" ""
			(at 264.16 121.92 0)
			(effects
				(font
					(size 1.27 1.27)
				)
				(hide yes)
			)
		)
		(property "Author" "Antmicro"
			(at 273.05 129.54 0)
			(effects
				(font
					(size 1.27 1.27)
					(thickness 0.15)
				)
				(justify left bottom)
				(hide yes)
			)
		)
		(property "License" "Apache-2.0"
			(at 273.05 132.08 0)
			(effects
				(font
					(size 1.27 1.27)
					(thickness 0.15)
				)
				(justify left bottom)
				(hide yes)
			)
		)
		(pin "1"
		)
		(instances
			(project "OCuLink to 10GbE adapter"
				(path ""
					(reference "#PWR0251")
					(unit 1)
				)
			)
		)
	)
	(symbol
		(lib_id "antmicroCapacitors0402:C_100n_0402")
		(at 53.34 229.87 90)
		(unit 1)
		(exclude_from_sim no)
		(in_bom yes)
		(on_board yes)
		(dnp no)
		(property "Reference" "C71"
			(at 55.372 226.06 90)
			(effects
				(font
					(size 1.27 1.27)
					(thickness 0.15)
				)
				(justify right)
			)
		)
		(property "Value" "C_100n_0402"
			(at 76.2 214.63 0)
			(effects
				(font
					(size 1.27 1.27)
					(thickness 0.15)
				)
				(justify left bottom)
				(hide yes)
			)
		)
		(property "Footprint" "antmicro-footprints:C_0402_1005Metric"
			(at 78.74 214.63 0)
			(effects
				(font
					(size 1.27 1.27)
					(thickness 0.15)
				)
				(justify left bottom)
				(hide yes)
			)
		)
		(property "Datasheet" "https://www.murata.com/products/productdetail?partno=GRM155R61H104KE14%23"
			(at 81.28 214.63 0)
			(effects
				(font
					(size 1.27 1.27)
					(thickness 0.15)
				)
				(justify left bottom)
				(hide yes)
			)
		)
		(property "Description" "SMD Multilayer Ceramic Capacitor, 0.1 µF, 50 V, 0402 [1005 Metric], ± 10%, X5R, GRM Series"
			(at 53.34 229.87 0)
			(effects
				(font
					(size 1.27 1.27)
				)
				(hide yes)
			)
		)
		(property "MPN" "GRM155R61H104KE14D"
			(at 83.82 214.63 0)
			(effects
				(font
					(size 1.27 1.27)
					(thickness 0.15)
				)
				(justify left bottom)
				(hide yes)
			)
		)
		(property "Val" "100n"
			(at 55.372 228.6 90)
			(effects
				(font
					(size 1.27 1.27)
					(thickness 0.15)
				)
				(justify right)
			)
		)
		(property "Voltage" "50V"
			(at 63.5 214.63 0)
			(effects
				(font
					(size 1.27 1.27)
					(thickness 0.15)
				)
				(justify left bottom)
				(hide yes)
			)
		)
		(property "Dielectric" "X5R"
			(at 66.04 214.63 0)
			(effects
				(font
					(size 1.27 1.27)
					(thickness 0.15)
				)
				(justify left bottom)
				(hide yes)
			)
		)
		(property "Manufacturer" "Murata"
			(at 68.58 214.63 0)
			(effects
				(font
					(size 1.27 1.27)
					(thickness 0.15)
				)
				(justify left bottom)
				(hide yes)
			)
		)
		(property "License" "Apache-2.0"
			(at 71.12 214.63 0)
			(effects
				(font
					(size 1.27 1.27)
					(thickness 0.15)
				)
				(justify left bottom)
				(hide yes)
			)
		)
		(property "Author" "Antmicro"
			(at 73.66 214.63 0)
			(effects
				(font
					(size 1.27 1.27)
					(thickness 0.15)
				)
				(justify left bottom)
				(hide yes)
			)
		)
		(pin "2"
		)
		(pin "1"
		)
		(instances
			(project "OCuLink to 10GbE adapter"
				(path ""
					(reference "C71")
					(unit 1)
				)
			)
		)
	)
	(symbol
		(lib_id "antmicroResistors0402:R_150R_0402")
		(at 142.24 233.68 90)
		(unit 1)
		(exclude_from_sim no)
		(in_bom yes)
		(on_board yes)
		(dnp no)
		(property "Reference" "R46"
			(at 143.51 229.87 90)
			(effects
				(font
					(size 1.27 1.27)
					(thickness 0.15)
				)
				(justify right)
			)
		)
		(property "Value" "R_150R_0402"
			(at 154.94 213.36 0)
			(effects
				(font
					(size 1.27 1.27)
					(thickness 0.15)
				)
				(justify left bottom)
				(hide yes)
			)
		)
		(property "Footprint" "antmicro-footprints:R_0402_1005Metric"
			(at 157.48 213.36 0)
			(effects
				(font
					(size 1.27 1.27)
					(thickness 0.15)
				)
				(justify left bottom)
				(hide yes)
			)
		)
		(property "Datasheet" "https://www.bourns.com/docs/product-datasheets/cr.pdf"
			(at 160.02 213.36 0)
			(effects
				(font
					(size 1.27 1.27)
					(thickness 0.15)
				)
				(justify left bottom)
				(hide yes)
			)
		)
		(property "Description" "SMD Chip Resistor, 150 ohm, ± 1%, 62.5 mW, 0402 [1005 Metric], Thick Film, General Purpose"
			(at 142.24 233.68 0)
			(effects
				(font
					(size 1.27 1.27)
				)
				(hide yes)
			)
		)
		(property "MPN" "CR0402-FX-1500GLF"
			(at 162.56 213.36 0)
			(effects
				(font
					(size 1.27 1.27)
					(thickness 0.15)
				)
				(justify left bottom)
				(hide yes)
			)
		)
		(property "Manufacturer" "Bourns"
			(at 165.1 213.36 0)
			(effects
				(font
					(size 1.27 1.27)
					(thickness 0.15)
				)
				(justify left bottom)
				(hide yes)
			)
		)
		(property "License" "Apache-2.0"
			(at 167.64 213.36 0)
			(effects
				(font
					(size 1.27 1.27)
					(thickness 0.15)
				)
				(justify left bottom)
				(hide yes)
			)
		)
		(property "Author" "Antmicro"
			(at 170.18 213.36 0)
			(effects
				(font
					(size 1.27 1.27)
					(thickness 0.15)
				)
				(justify left bottom)
				(hide yes)
			)
		)
		(property "Val" "150R"
			(at 143.51 232.41 90)
			(effects
				(font
					(size 1.27 1.27)
					(thickness 0.15)
				)
				(justify right)
			)
		)
		(property "Tolerance" "1%"
			(at 152.4 213.36 0)
			(effects
				(font
					(size 1.27 1.27)
				)
				(justify left bottom)
				(hide yes)
			)
		)
		(pin "2"
		)
		(pin "1"
		)
		(instances
			(project "OCuLink to 10GbE adapter"
				(path ""
					(reference "R46")
					(unit 1)
				)
			)
		)
	)
	(symbol
		(lib_id "antmicroCapacitors0402:C_100n_0402")
		(at 168.91 223.52 180)
		(unit 1)
		(exclude_from_sim no)
		(in_bom yes)
		(on_board yes)
		(dnp no)
		(property "Reference" "C68"
			(at 164.592 222.25 0)
			(effects
				(font
					(size 1.27 1.27)
					(thickness 0.15)
				)
				(justify left)
			)
		)
		(property "Value" "C_100n_0402"
			(at 153.67 200.66 0)
			(effects
				(font
					(size 1.27 1.27)
					(thickness 0.15)
				)
				(justify left bottom)
				(hide yes)
			)
		)
		(property "Footprint" "antmicro-footprints:C_0402_1005Metric"
			(at 153.67 198.12 0)
			(effects
				(font
					(size 1.27 1.27)
					(thickness 0.15)
				)
				(justify left bottom)
				(hide yes)
			)
		)
		(property "Datasheet" "https://www.murata.com/products/productdetail?partno=GRM155R61H104KE14%23"
			(at 153.67 195.58 0)
			(effects
				(font
					(size 1.27 1.27)
					(thickness 0.15)
				)
				(justify left bottom)
				(hide yes)
			)
		)
		(property "Description" "SMD Multilayer Ceramic Capacitor, 0.1 µF, 50 V, 0402 [1005 Metric], ± 10%, X5R, GRM Series"
			(at 168.91 223.52 0)
			(effects
				(font
					(size 1.27 1.27)
				)
				(hide yes)
			)
		)
		(property "MPN" "GRM155R61H104KE14D"
			(at 153.67 193.04 0)
			(effects
				(font
					(size 1.27 1.27)
					(thickness 0.15)
				)
				(justify left bottom)
				(hide yes)
			)
		)
		(property "Val" "100n"
			(at 167.894 222.25 0)
			(effects
				(font
					(size 1.27 1.27)
					(thickness 0.15)
				)
				(justify right)
			)
		)
		(property "Voltage" "50V"
			(at 153.67 213.36 0)
			(effects
				(font
					(size 1.27 1.27)
					(thickness 0.15)
				)
				(justify left bottom)
				(hide yes)
			)
		)
		(property "Dielectric" "X5R"
			(at 153.67 210.82 0)
			(effects
				(font
					(size 1.27 1.27)
					(thickness 0.15)
				)
				(justify left bottom)
				(hide yes)
			)
		)
		(property "Manufacturer" "Murata"
			(at 153.67 208.28 0)
			(effects
				(font
					(size 1.27 1.27)
					(thickness 0.15)
				)
				(justify left bottom)
				(hide yes)
			)
		)
		(property "License" "Apache-2.0"
			(at 153.67 205.74 0)
			(effects
				(font
					(size 1.27 1.27)
					(thickness 0.15)
				)
				(justify left bottom)
				(hide yes)
			)
		)
		(property "Author" "Antmicro"
			(at 153.67 203.2 0)
			(effects
				(font
					(size 1.27 1.27)
					(thickness 0.15)
				)
				(justify left bottom)
				(hide yes)
			)
		)
		(pin "2"
		)
		(pin "1"
		)
		(instances
			(project "OCuLink to 10GbE adapter"
				(path ""
					(reference "C68")
					(unit 1)
				)
			)
		)
	)
	(symbol
		(lib_id "antmicroResistors0402:R_0R_0402")
		(at 153.67 203.2 0)
		(unit 1)
		(exclude_from_sim no)
		(in_bom yes)
		(on_board yes)
		(dnp no)
		(property "Reference" "R71"
			(at 153.67 201.93 0)
			(effects
				(font
					(size 1.27 1.27)
					(thickness 0.15)
				)
				(justify right)
			)
		)
		(property "Value" "R_0R_0402"
			(at 173.99 215.9 0)
			(effects
				(font
					(size 1.27 1.27)
					(thickness 0.15)
				)
				(justify left bottom)
				(hide yes)
			)
		)
		(property "Footprint" "antmicro-footprints:R_0402_1005Metric"
			(at 173.99 218.44 0)
			(effects
				(font
					(size 1.27 1.27)
					(thickness 0.15)
				)
				(justify left bottom)
				(hide yes)
			)
		)
		(property "Datasheet" "https://industrial.panasonic.com/cdbs/www-data/pdf/RDA0000/AOA0000C301.pdf"
			(at 173.99 220.98 0)
			(effects
				(font
					(size 1.27 1.27)
					(thickness 0.15)
				)
				(justify left bottom)
				(hide yes)
			)
		)
		(property "Description" "SMD Chip Resistor, Jumper, 0 ohm, 100 mW, 0402 [1005 Metric], Thick Film, General Purpose"
			(at 153.67 203.2 0)
			(effects
				(font
					(size 1.27 1.27)
				)
				(hide yes)
			)
		)
		(property "MPN" "ERJ2GE0R00X"
			(at 173.99 223.52 0)
			(effects
				(font
					(size 1.27 1.27)
					(thickness 0.15)
				)
				(justify left bottom)
				(hide yes)
			)
		)
		(property "Manufacturer" "Panasonic"
			(at 173.99 226.06 0)
			(effects
				(font
					(size 1.27 1.27)
					(thickness 0.15)
				)
				(justify left bottom)
				(hide yes)
			)
		)
		(property "License" "Apache-2.0"
			(at 173.99 228.6 0)
			(effects
				(font
					(size 1.27 1.27)
					(thickness 0.15)
				)
				(justify left bottom)
				(hide yes)
			)
		)
		(property "Author" "Antmicro"
			(at 173.99 231.14 0)
			(effects
				(font
					(size 1.27 1.27)
					(thickness 0.15)
				)
				(justify left bottom)
				(hide yes)
			)
		)
		(property "Val" "0R"
			(at 158.75 201.93 0)
			(effects
				(font
					(size 1.27 1.27)
					(thickness 0.15)
				)
				(justify left)
			)
		)
		(property "Tolerance" "~"
			(at 173.99 213.36 0)
			(effects
				(font
					(size 1.27 1.27)
				)
				(justify left bottom)
				(hide yes)
			)
		)
		(property "Current" "1A"
			(at 173.99 233.68 0)
			(effects
				(font
					(size 1.27 1.27)
					(thickness 0.15)
				)
				(justify left bottom)
				(hide yes)
			)
		)
		(pin "1"
		)
		(pin "2"
		)
		(instances
			(project "OCuLink to 10GbE adapter"
				(path ""
					(reference "R71")
					(unit 1)
				)
			)
		)
	)
	(symbol
		(lib_id "antmicroResistors0402:R_3k3_0402")
		(at 175.26 165.1 90)
		(unit 1)
		(exclude_from_sim no)
		(in_bom yes)
		(on_board yes)
		(dnp no)
		(property "Reference" "R66"
			(at 176.784 161.29 90)
			(effects
				(font
					(size 1.27 1.27)
					(thickness 0.15)
				)
				(justify right)
			)
		)
		(property "Value" "R_3k3_0402"
			(at 187.96 144.78 0)
			(effects
				(font
					(size 1.27 1.27)
					(thickness 0.15)
				)
				(justify left bottom)
				(hide yes)
			)
		)
		(property "Footprint" "antmicro-footprints:R_0402_1005Metric"
			(at 190.5 144.78 0)
			(effects
				(font
					(size 1.27 1.27)
					(thickness 0.15)
				)
				(justify left bottom)
				(hide yes)
			)
		)
		(property "Datasheet" "https://www.bourns.com/docs/product-datasheets/cr.pdf"
			(at 193.04 144.78 0)
			(effects
				(font
					(size 1.27 1.27)
					(thickness 0.15)
				)
				(justify left bottom)
				(hide yes)
			)
		)
		(property "Description" "SMD Chip Resistor, 3.3 kohm, ± 1%, 63 mW, 0402 [1005 Metric], Thick Film, General Purpose"
			(at 175.26 165.1 0)
			(effects
				(font
					(size 1.27 1.27)
				)
				(hide yes)
			)
		)
		(property "MPN" "CR0402-FX-3301GLF"
			(at 195.58 144.78 0)
			(effects
				(font
					(size 1.27 1.27)
					(thickness 0.15)
				)
				(justify left bottom)
				(hide yes)
			)
		)
		(property "Manufacturer" "Bourns"
			(at 198.12 144.78 0)
			(effects
				(font
					(size 1.27 1.27)
					(thickness 0.15)
				)
				(justify left bottom)
				(hide yes)
			)
		)
		(property "License" "Apache-2.0"
			(at 200.66 144.78 0)
			(effects
				(font
					(size 1.27 1.27)
					(thickness 0.15)
				)
				(justify left bottom)
				(hide yes)
			)
		)
		(property "Author" "Antmicro"
			(at 203.2 144.78 0)
			(effects
				(font
					(size 1.27 1.27)
					(thickness 0.15)
				)
				(justify left bottom)
				(hide yes)
			)
		)
		(property "Val" "3k3"
			(at 176.784 163.83 90)
			(effects
				(font
					(size 1.27 1.27)
					(thickness 0.15)
				)
				(justify right)
			)
		)
		(property "Tolerance" "1%"
			(at 185.42 144.78 0)
			(effects
				(font
					(size 1.27 1.27)
				)
				(justify left bottom)
				(hide yes)
			)
		)
		(pin "2"
		)
		(pin "1"
		)
		(instances
			(project "OCuLink to 10GbE adapter"
				(path ""
					(reference "R66")
					(unit 1)
				)
			)
		)
	)
	(symbol
		(lib_id "antmicroCapacitors0402:C_10p_0402")
		(at 100.33 180.34 90)
		(unit 1)
		(exclude_from_sim no)
		(in_bom yes)
		(on_board yes)
		(dnp no)
		(property "Reference" "C215"
			(at 102.108 176.53 90)
			(effects
				(font
					(size 1.27 1.27)
					(thickness 0.15)
				)
				(justify right)
			)
		)
		(property "Value" "C_10p_0402"
			(at 110.49 160.02 0)
			(effects
				(font
					(size 1.27 1.27)
					(thickness 0.15)
				)
				(justify left bottom)
				(hide yes)
			)
		)
		(property "Footprint" "antmicro-footprints:C_0402_1005Metric"
			(at 113.03 160.02 0)
			(effects
				(font
					(size 1.27 1.27)
					(thickness 0.15)
				)
				(justify left bottom)
				(hide yes)
			)
		)
		(property "Datasheet" "https://www.murata.com/products/productdetail?partno=GCM1555C1H100GA16%23"
			(at 115.57 160.02 0)
			(effects
				(font
					(size 1.27 1.27)
					(thickness 0.15)
				)
				(justify left bottom)
				(hide yes)
			)
		)
		(property "Description" "SMD Multilayer Ceramic Capacitor, 10 pF, 50 V, 0402 [1005 Metric], ± 2%, C0G / NP0, GCM"
			(at 133.35 160.02 0)
			(effects
				(font
					(size 1.27 1.27)
				)
				(justify left bottom)
				(hide yes)
			)
		)
		(property "MPN" "GCM1555C1H100GA16D"
			(at 118.11 160.02 0)
			(effects
				(font
					(size 1.27 1.27)
					(thickness 0.15)
				)
				(justify left bottom)
				(hide yes)
			)
		)
		(property "Manufacturer" "Murata"
			(at 120.65 160.02 0)
			(effects
				(font
					(size 1.27 1.27)
					(thickness 0.15)
				)
				(justify left bottom)
				(hide yes)
			)
		)
		(property "License" "Apache-2.0"
			(at 123.19 160.02 0)
			(effects
				(font
					(size 1.27 1.27)
					(thickness 0.15)
				)
				(justify left bottom)
				(hide yes)
			)
		)
		(property "Author" "Antmicro"
			(at 125.73 160.02 0)
			(effects
				(font
					(size 1.27 1.27)
					(thickness 0.15)
				)
				(justify left bottom)
				(hide yes)
			)
		)
		(property "Val" "10p"
			(at 102.108 179.07 90)
			(effects
				(font
					(size 1.27 1.27)
					(thickness 0.15)
				)
				(justify right)
			)
		)
		(property "Voltage" "50V"
			(at 128.27 160.02 0)
			(effects
				(font
					(size 1.27 1.27)
				)
				(justify left bottom)
				(hide yes)
			)
		)
		(property "Dielectric" "C0G"
			(at 130.81 160.02 0)
			(effects
				(font
					(size 1.27 1.27)
				)
				(justify left bottom)
				(hide yes)
			)
		)
		(pin "2"
		)
		(pin "1"
		)
		(instances
			(project "oculink-to-10gbe-adapter"
				(path ""
					(reference "C215")
					(unit 1)
				)
			)
		)
	)
	(symbol
		(lib_id "antmicropower:GND")
		(at 78.74 236.22 0)
		(unit 1)
		(exclude_from_sim no)
		(in_bom yes)
		(on_board yes)
		(dnp no)
		(property "Reference" "#PWR092"
			(at 87.63 238.76 0)
			(effects
				(font
					(size 1.27 1.27)
					(thickness 0.15)
				)
				(justify left bottom)
				(hide yes)
			)
		)
		(property "Value" "GND"
			(at 78.74 240.03 0)
			(effects
				(font
					(size 1.27 1.27)
					(thickness 0.15)
				)
			)
		)
		(property "Footprint" ""
			(at 87.63 243.84 0)
			(effects
				(font
					(size 1.27 1.27)
					(thickness 0.15)
				)
				(justify left bottom)
				(hide yes)
			)
		)
		(property "Datasheet" ""
			(at 87.63 248.92 0)
			(effects
				(font
					(size 1.27 1.27)
					(thickness 0.15)
				)
				(justify left bottom)
				(hide yes)
			)
		)
		(property "Description" ""
			(at 78.74 236.22 0)
			(effects
				(font
					(size 1.27 1.27)
				)
				(hide yes)
			)
		)
		(property "Author" "Antmicro"
			(at 87.63 243.84 0)
			(effects
				(font
					(size 1.27 1.27)
					(thickness 0.15)
				)
				(justify left bottom)
				(hide yes)
			)
		)
		(property "License" "Apache-2.0"
			(at 87.63 246.38 0)
			(effects
				(font
					(size 1.27 1.27)
					(thickness 0.15)
				)
				(justify left bottom)
				(hide yes)
			)
		)
		(pin "1"
		)
		(instances
			(project "OCuLink to 10GbE adapter"
				(path ""
					(reference "#PWR092")
					(unit 1)
				)
			)
		)
	)
	(symbol
		(lib_id "antmicroResistors0402:R_8k2_0402")
		(at 175.26 241.3 90)
		(unit 1)
		(exclude_from_sim no)
		(in_bom yes)
		(on_board yes)
		(dnp no)
		(property "Reference" "R76"
			(at 176.784 237.49 90)
			(effects
				(font
					(size 1.27 1.27)
					(thickness 0.15)
				)
				(justify right)
			)
		)
		(property "Value" "R_8k2_0402"
			(at 187.96 220.98 0)
			(effects
				(font
					(size 1.27 1.27)
					(thickness 0.15)
				)
				(justify left bottom)
				(hide yes)
			)
		)
		(property "Footprint" "antmicro-footprints:R_0402_1005Metric"
			(at 190.5 220.98 0)
			(effects
				(font
					(size 1.27 1.27)
					(thickness 0.15)
				)
				(justify left bottom)
				(hide yes)
			)
		)
		(property "Datasheet" "https://www.bourns.com/docs/product-datasheets/cr.pdf"
			(at 193.04 220.98 0)
			(effects
				(font
					(size 1.27 1.27)
					(thickness 0.15)
				)
				(justify left bottom)
				(hide yes)
			)
		)
		(property "Description" "SMD Chip Resistor"
			(at 175.26 241.3 0)
			(effects
				(font
					(size 1.27 1.27)
				)
				(hide yes)
			)
		)
		(property "MPN" "CR0402-FX-8201GLF"
			(at 195.58 220.98 0)
			(effects
				(font
					(size 1.27 1.27)
					(thickness 0.15)
				)
				(justify left bottom)
				(hide yes)
			)
		)
		(property "Manufacturer" "Bourns"
			(at 198.12 220.98 0)
			(effects
				(font
					(size 1.27 1.27)
					(thickness 0.15)
				)
				(justify left bottom)
				(hide yes)
			)
		)
		(property "License" "Apache-2.0"
			(at 200.66 220.98 0)
			(effects
				(font
					(size 1.27 1.27)
					(thickness 0.15)
				)
				(justify left bottom)
				(hide yes)
			)
		)
		(property "Author" "Antmicro"
			(at 203.2 220.98 0)
			(effects
				(font
					(size 1.27 1.27)
					(thickness 0.15)
				)
				(justify left bottom)
				(hide yes)
			)
		)
		(property "Val" "8k2"
			(at 176.784 240.03 90)
			(effects
				(font
					(size 1.27 1.27)
					(thickness 0.15)
				)
				(justify right)
			)
		)
		(property "Tolerance" "1%"
			(at 185.42 220.98 0)
			(effects
				(font
					(size 1.27 1.27)
				)
				(justify left bottom)
				(hide yes)
			)
		)
		(pin "2"
		)
		(pin "1"
		)
		(instances
			(project ""
				(path ""
					(reference "R76")
					(unit 1)
				)
			)
		)
	)
	(symbol
		(lib_id "antmicropower:+3V3")
		(at 175.26 154.94 0)
		(unit 1)
		(exclude_from_sim no)
		(in_bom yes)
		(on_board yes)
		(dnp no)
		(property "Reference" "#PWR0252"
			(at 190.5 154.94 0)
			(effects
				(font
					(size 1.27 1.27)
					(thickness 0.15)
				)
				(justify left bottom)
				(hide yes)
			)
		)
		(property "Value" "+3V3"
			(at 175.26 151.13 0)
			(effects
				(font
					(size 1.27 1.27)
					(thickness 0.15)
				)
			)
		)
		(property "Footprint" ""
			(at 190.5 162.56 0)
			(effects
				(font
					(size 1.27 1.27)
					(thickness 0.15)
				)
				(justify left bottom)
				(hide yes)
			)
		)
		(property "Datasheet" ""
			(at 190.5 165.1 0)
			(effects
				(font
					(size 1.27 1.27)
					(thickness 0.15)
				)
				(justify left bottom)
				(hide yes)
			)
		)
		(property "Description" ""
			(at 175.26 154.94 0)
			(effects
				(font
					(size 1.27 1.27)
				)
				(hide yes)
			)
		)
		(property "Author" "Antmicro"
			(at 190.5 157.48 0)
			(effects
				(font
					(size 1.27 1.27)
					(thickness 0.15)
				)
				(justify left bottom)
				(hide yes)
			)
		)
		(property "License" "Apache-2.0"
			(at 190.5 160.02 0)
			(effects
				(font
					(size 1.27 1.27)
					(thickness 0.15)
				)
				(justify left bottom)
				(hide yes)
			)
		)
		(pin "1"
		)
		(instances
			(project "OCuLink to 10GbE adapter"
				(path ""
					(reference "#PWR0252")
					(unit 1)
				)
			)
		)
	)
	(symbol
		(lib_id "antmicroResistors0402:R_3k3_0402")
		(at 152.4 165.1 90)
		(unit 1)
		(exclude_from_sim no)
		(in_bom yes)
		(on_board yes)
		(dnp no)
		(property "Reference" "R63"
			(at 153.924 161.29 90)
			(effects
				(font
					(size 1.27 1.27)
					(thickness 0.15)
				)
				(justify right)
			)
		)
		(property "Value" "R_3k3_0402"
			(at 165.1 144.78 0)
			(effects
				(font
					(size 1.27 1.27)
					(thickness 0.15)
				)
				(justify left bottom)
				(hide yes)
			)
		)
		(property "Footprint" "antmicro-footprints:R_0402_1005Metric"
			(at 167.64 144.78 0)
			(effects
				(font
					(size 1.27 1.27)
					(thickness 0.15)
				)
				(justify left bottom)
				(hide yes)
			)
		)
		(property "Datasheet" "https://www.bourns.com/docs/product-datasheets/cr.pdf"
			(at 170.18 144.78 0)
			(effects
				(font
					(size 1.27 1.27)
					(thickness 0.15)
				)
				(justify left bottom)
				(hide yes)
			)
		)
		(property "Description" "SMD Chip Resistor, 3.3 kohm, ± 1%, 63 mW, 0402 [1005 Metric], Thick Film, General Purpose"
			(at 152.4 165.1 0)
			(effects
				(font
					(size 1.27 1.27)
				)
				(hide yes)
			)
		)
		(property "MPN" "CR0402-FX-3301GLF"
			(at 172.72 144.78 0)
			(effects
				(font
					(size 1.27 1.27)
					(thickness 0.15)
				)
				(justify left bottom)
				(hide yes)
			)
		)
		(property "Manufacturer" "Bourns"
			(at 175.26 144.78 0)
			(effects
				(font
					(size 1.27 1.27)
					(thickness 0.15)
				)
				(justify left bottom)
				(hide yes)
			)
		)
		(property "License" "Apache-2.0"
			(at 177.8 144.78 0)
			(effects
				(font
					(size 1.27 1.27)
					(thickness 0.15)
				)
				(justify left bottom)
				(hide yes)
			)
		)
		(property "Author" "Antmicro"
			(at 180.34 144.78 0)
			(effects
				(font
					(size 1.27 1.27)
					(thickness 0.15)
				)
				(justify left bottom)
				(hide yes)
			)
		)
		(property "Val" "3k3"
			(at 153.924 163.83 90)
			(effects
				(font
					(size 1.27 1.27)
					(thickness 0.15)
				)
				(justify right)
			)
		)
		(property "Tolerance" "1%"
			(at 162.56 144.78 0)
			(effects
				(font
					(size 1.27 1.27)
				)
				(justify left bottom)
				(hide yes)
			)
		)
		(pin "2"
		)
		(pin "1"
		)
		(instances
			(project "OCuLink to 10GbE adapter"
				(path ""
					(reference "R63")
					(unit 1)
				)
			)
		)
	)
	(symbol
		(lib_id "antmicroResistors0402:R_3k3_0402")
		(at 167.64 165.1 90)
		(unit 1)
		(exclude_from_sim no)
		(in_bom yes)
		(on_board yes)
		(dnp no)
		(property "Reference" "R65"
			(at 169.164 161.29 90)
			(effects
				(font
					(size 1.27 1.27)
					(thickness 0.15)
				)
				(justify right)
			)
		)
		(property "Value" "R_3k3_0402"
			(at 180.34 144.78 0)
			(effects
				(font
					(size 1.27 1.27)
					(thickness 0.15)
				)
				(justify left bottom)
				(hide yes)
			)
		)
		(property "Footprint" "antmicro-footprints:R_0402_1005Metric"
			(at 182.88 144.78 0)
			(effects
				(font
					(size 1.27 1.27)
					(thickness 0.15)
				)
				(justify left bottom)
				(hide yes)
			)
		)
		(property "Datasheet" "https://www.bourns.com/docs/product-datasheets/cr.pdf"
			(at 185.42 144.78 0)
			(effects
				(font
					(size 1.27 1.27)
					(thickness 0.15)
				)
				(justify left bottom)
				(hide yes)
			)
		)
		(property "Description" "SMD Chip Resistor, 3.3 kohm, ± 1%, 63 mW, 0402 [1005 Metric], Thick Film, General Purpose"
			(at 167.64 165.1 0)
			(effects
				(font
					(size 1.27 1.27)
				)
				(hide yes)
			)
		)
		(property "MPN" "CR0402-FX-3301GLF"
			(at 187.96 144.78 0)
			(effects
				(font
					(size 1.27 1.27)
					(thickness 0.15)
				)
				(justify left bottom)
				(hide yes)
			)
		)
		(property "Manufacturer" "Bourns"
			(at 190.5 144.78 0)
			(effects
				(font
					(size 1.27 1.27)
					(thickness 0.15)
				)
				(justify left bottom)
				(hide yes)
			)
		)
		(property "License" "Apache-2.0"
			(at 193.04 144.78 0)
			(effects
				(font
					(size 1.27 1.27)
					(thickness 0.15)
				)
				(justify left bottom)
				(hide yes)
			)
		)
		(property "Author" "Antmicro"
			(at 195.58 144.78 0)
			(effects
				(font
					(size 1.27 1.27)
					(thickness 0.15)
				)
				(justify left bottom)
				(hide yes)
			)
		)
		(property "Val" "3k3"
			(at 169.164 163.83 90)
			(effects
				(font
					(size 1.27 1.27)
					(thickness 0.15)
				)
				(justify right)
			)
		)
		(property "Tolerance" "1%"
			(at 177.8 144.78 0)
			(effects
				(font
					(size 1.27 1.27)
				)
				(justify left bottom)
				(hide yes)
			)
		)
		(pin "2"
		)
		(pin "1"
		)
		(instances
			(project "OCuLink to 10GbE adapter"
				(path ""
					(reference "R65")
					(unit 1)
				)
			)
		)
	)
	(symbol
		(lib_id "antmicropower:GND")
		(at 261.62 241.3 0)
		(unit 1)
		(exclude_from_sim no)
		(in_bom yes)
		(on_board yes)
		(dnp no)
		(property "Reference" "#PWR0256"
			(at 270.51 243.84 0)
			(effects
				(font
					(size 1.27 1.27)
					(thickness 0.15)
				)
				(justify left bottom)
				(hide yes)
			)
		)
		(property "Value" "GND"
			(at 261.62 245.11 0)
			(effects
				(font
					(size 1.27 1.27)
					(thickness 0.15)
				)
			)
		)
		(property "Footprint" ""
			(at 270.51 248.92 0)
			(effects
				(font
					(size 1.27 1.27)
					(thickness 0.15)
				)
				(justify left bottom)
				(hide yes)
			)
		)
		(property "Datasheet" ""
			(at 270.51 254 0)
			(effects
				(font
					(size 1.27 1.27)
					(thickness 0.15)
				)
				(justify left bottom)
				(hide yes)
			)
		)
		(property "Description" ""
			(at 261.62 241.3 0)
			(effects
				(font
					(size 1.27 1.27)
				)
				(hide yes)
			)
		)
		(property "Author" "Antmicro"
			(at 270.51 248.92 0)
			(effects
				(font
					(size 1.27 1.27)
					(thickness 0.15)
				)
				(justify left bottom)
				(hide yes)
			)
		)
		(property "License" "Apache-2.0"
			(at 270.51 251.46 0)
			(effects
				(font
					(size 1.27 1.27)
					(thickness 0.15)
				)
				(justify left bottom)
				(hide yes)
			)
		)
		(pin "1"
		)
		(instances
			(project "OCuLink to 10GbE adapter"
				(path ""
					(reference "#PWR0256")
					(unit 1)
				)
			)
		)
	)
	(symbol
		(lib_id "antmicroResistors0402:R_10k_0402")
		(at 64.77 226.06 0)
		(unit 1)
		(exclude_from_sim no)
		(in_bom yes)
		(on_board yes)
		(dnp no)
		(property "Reference" "R43"
			(at 67.31 223.774 0)
			(effects
				(font
					(size 1.27 1.27)
					(thickness 0.15)
				)
			)
		)
		(property "Value" "R_10k_0402"
			(at 85.09 238.76 0)
			(effects
				(font
					(size 1.27 1.27)
					(thickness 0.15)
				)
				(justify left bottom)
				(hide yes)
			)
		)
		(property "Footprint" "antmicro-footprints:R_0402_1005Metric"
			(at 85.09 241.3 0)
			(effects
				(font
					(size 1.27 1.27)
					(thickness 0.15)
				)
				(justify left bottom)
				(hide yes)
			)
		)
		(property "Datasheet" "https://www.bourns.com/docs/product-datasheets/cr.pdf"
			(at 85.09 243.84 0)
			(effects
				(font
					(size 1.27 1.27)
					(thickness 0.15)
				)
				(justify left bottom)
				(hide yes)
			)
		)
		(property "Description" "SMD Chip Resistor, 10 kohm, ± 1%, 62.5 mW, 0402 [1005 Metric], Thick Film, General Purpose"
			(at 64.77 226.06 0)
			(effects
				(font
					(size 1.27 1.27)
				)
				(hide yes)
			)
		)
		(property "MPN" "CR0402-FX-1002GLF"
			(at 85.09 246.38 0)
			(effects
				(font
					(size 1.27 1.27)
					(thickness 0.15)
				)
				(justify left bottom)
				(hide yes)
			)
		)
		(property "Manufacturer" "Bourns"
			(at 85.09 248.92 0)
			(effects
				(font
					(size 1.27 1.27)
					(thickness 0.15)
				)
				(justify left bottom)
				(hide yes)
			)
		)
		(property "License" "Apache-2.0"
			(at 85.09 251.46 0)
			(effects
				(font
					(size 1.27 1.27)
					(thickness 0.15)
				)
				(justify left bottom)
				(hide yes)
			)
		)
		(property "Author" "Antmicro"
			(at 85.09 254 0)
			(effects
				(font
					(size 1.27 1.27)
					(thickness 0.15)
				)
				(justify left bottom)
				(hide yes)
			)
		)
		(property "Val" "10k"
			(at 67.31 228.346 0)
			(effects
				(font
					(size 1.27 1.27)
					(thickness 0.15)
				)
			)
		)
		(property "Tolerance" "1%"
			(at 85.09 236.22 0)
			(effects
				(font
					(size 1.27 1.27)
				)
				(justify left bottom)
				(hide yes)
			)
		)
		(pin "1"
		)
		(pin "2"
		)
		(instances
			(project "OCuLink to 10GbE adapter"
				(path ""
					(reference "R43")
					(unit 1)
				)
			)
		)
	)
	(symbol
		(lib_id "antmicroResistors0402:R_0R_0402")
		(at 153.67 200.66 0)
		(unit 1)
		(exclude_from_sim no)
		(in_bom yes)
		(on_board yes)
		(dnp no)
		(property "Reference" "R70"
			(at 153.67 199.39 0)
			(effects
				(font
					(size 1.27 1.27)
					(thickness 0.15)
				)
				(justify right)
			)
		)
		(property "Value" "R_0R_0402"
			(at 173.99 213.36 0)
			(effects
				(font
					(size 1.27 1.27)
					(thickness 0.15)
				)
				(justify left bottom)
				(hide yes)
			)
		)
		(property "Footprint" "antmicro-footprints:R_0402_1005Metric"
			(at 173.99 215.9 0)
			(effects
				(font
					(size 1.27 1.27)
					(thickness 0.15)
				)
				(justify left bottom)
				(hide yes)
			)
		)
		(property "Datasheet" "https://industrial.panasonic.com/cdbs/www-data/pdf/RDA0000/AOA0000C301.pdf"
			(at 173.99 218.44 0)
			(effects
				(font
					(size 1.27 1.27)
					(thickness 0.15)
				)
				(justify left bottom)
				(hide yes)
			)
		)
		(property "Description" "SMD Chip Resistor, Jumper, 0 ohm, 100 mW, 0402 [1005 Metric], Thick Film, General Purpose"
			(at 153.67 200.66 0)
			(effects
				(font
					(size 1.27 1.27)
				)
				(hide yes)
			)
		)
		(property "MPN" "ERJ2GE0R00X"
			(at 173.99 220.98 0)
			(effects
				(font
					(size 1.27 1.27)
					(thickness 0.15)
				)
				(justify left bottom)
				(hide yes)
			)
		)
		(property "Manufacturer" "Panasonic"
			(at 173.99 223.52 0)
			(effects
				(font
					(size 1.27 1.27)
					(thickness 0.15)
				)
				(justify left bottom)
				(hide yes)
			)
		)
		(property "License" "Apache-2.0"
			(at 173.99 226.06 0)
			(effects
				(font
					(size 1.27 1.27)
					(thickness 0.15)
				)
				(justify left bottom)
				(hide yes)
			)
		)
		(property "Author" "Antmicro"
			(at 173.99 228.6 0)
			(effects
				(font
					(size 1.27 1.27)
					(thickness 0.15)
				)
				(justify left bottom)
				(hide yes)
			)
		)
		(property "Val" "0R"
			(at 158.75 199.39 0)
			(effects
				(font
					(size 1.27 1.27)
					(thickness 0.15)
				)
				(justify left)
			)
		)
		(property "Tolerance" "~"
			(at 173.99 210.82 0)
			(effects
				(font
					(size 1.27 1.27)
				)
				(justify left bottom)
				(hide yes)
			)
		)
		(property "Current" "1A"
			(at 173.99 231.14 0)
			(effects
				(font
					(size 1.27 1.27)
					(thickness 0.15)
				)
				(justify left bottom)
				(hide yes)
			)
		)
		(pin "1"
		)
		(pin "2"
		)
		(instances
			(project "OCuLink to 10GbE adapter"
				(path ""
					(reference "R70")
					(unit 1)
				)
			)
		)
	)
	(symbol
		(lib_id "antmicroResistors0402:R_150R_0402")
		(at 133.35 233.68 90)
		(unit 1)
		(exclude_from_sim no)
		(in_bom yes)
		(on_board yes)
		(dnp no)
		(property "Reference" "R45"
			(at 134.62 229.87 90)
			(effects
				(font
					(size 1.27 1.27)
					(thickness 0.15)
				)
				(justify right)
			)
		)
		(property "Value" "R_150R_0402"
			(at 146.05 213.36 0)
			(effects
				(font
					(size 1.27 1.27)
					(thickness 0.15)
				)
				(justify left bottom)
				(hide yes)
			)
		)
		(property "Footprint" "antmicro-footprints:R_0402_1005Metric"
			(at 148.59 213.36 0)
			(effects
				(font
					(size 1.27 1.27)
					(thickness 0.15)
				)
				(justify left bottom)
				(hide yes)
			)
		)
		(property "Datasheet" "https://www.bourns.com/docs/product-datasheets/cr.pdf"
			(at 151.13 213.36 0)
			(effects
				(font
					(size 1.27 1.27)
					(thickness 0.15)
				)
				(justify left bottom)
				(hide yes)
			)
		)
		(property "Description" "SMD Chip Resistor, 150 ohm, ± 1%, 62.5 mW, 0402 [1005 Metric], Thick Film, General Purpose"
			(at 133.35 233.68 0)
			(effects
				(font
					(size 1.27 1.27)
				)
				(hide yes)
			)
		)
		(property "MPN" "CR0402-FX-1500GLF"
			(at 153.67 213.36 0)
			(effects
				(font
					(size 1.27 1.27)
					(thickness 0.15)
				)
				(justify left bottom)
				(hide yes)
			)
		)
		(property "Manufacturer" "Bourns"
			(at 156.21 213.36 0)
			(effects
				(font
					(size 1.27 1.27)
					(thickness 0.15)
				)
				(justify left bottom)
				(hide yes)
			)
		)
		(property "License" "Apache-2.0"
			(at 158.75 213.36 0)
			(effects
				(font
					(size 1.27 1.27)
					(thickness 0.15)
				)
				(justify left bottom)
				(hide yes)
			)
		)
		(property "Author" "Antmicro"
			(at 161.29 213.36 0)
			(effects
				(font
					(size 1.27 1.27)
					(thickness 0.15)
				)
				(justify left bottom)
				(hide yes)
			)
		)
		(property "Val" "150R"
			(at 134.62 232.41 90)
			(effects
				(font
					(size 1.27 1.27)
					(thickness 0.15)
				)
				(justify right)
			)
		)
		(property "Tolerance" "1%"
			(at 143.51 213.36 0)
			(effects
				(font
					(size 1.27 1.27)
				)
				(justify left bottom)
				(hide yes)
			)
		)
		(pin "2"
		)
		(pin "1"
		)
		(instances
			(project "OCuLink to 10GbE adapter"
				(path ""
					(reference "R45")
					(unit 1)
				)
			)
		)
	)
	(symbol
		(lib_id "antmicropower:+3V3")
		(at 175.26 233.68 0)
		(unit 1)
		(exclude_from_sim no)
		(in_bom yes)
		(on_board yes)
		(dnp no)
		(property "Reference" "#PWR0254"
			(at 190.5 233.68 0)
			(effects
				(font
					(size 1.27 1.27)
					(thickness 0.15)
				)
				(justify left bottom)
				(hide yes)
			)
		)
		(property "Value" "+3V3"
			(at 175.26 229.87 0)
			(effects
				(font
					(size 1.27 1.27)
					(thickness 0.15)
				)
			)
		)
		(property "Footprint" ""
			(at 190.5 241.3 0)
			(effects
				(font
					(size 1.27 1.27)
					(thickness 0.15)
				)
				(justify left bottom)
				(hide yes)
			)
		)
		(property "Datasheet" ""
			(at 190.5 243.84 0)
			(effects
				(font
					(size 1.27 1.27)
					(thickness 0.15)
				)
				(justify left bottom)
				(hide yes)
			)
		)
		(property "Description" ""
			(at 175.26 233.68 0)
			(effects
				(font
					(size 1.27 1.27)
				)
				(hide yes)
			)
		)
		(property "Author" "Antmicro"
			(at 190.5 236.22 0)
			(effects
				(font
					(size 1.27 1.27)
					(thickness 0.15)
				)
				(justify left bottom)
				(hide yes)
			)
		)
		(property "License" "Apache-2.0"
			(at 190.5 238.76 0)
			(effects
				(font
					(size 1.27 1.27)
					(thickness 0.15)
				)
				(justify left bottom)
				(hide yes)
			)
		)
		(pin "1"
		)
		(instances
			(project "OCuLink to 10GbE adapter"
				(path ""
					(reference "#PWR0254")
					(unit 1)
				)
			)
		)
	)
	(symbol
		(lib_id "antmicropower:GND")
		(at 255.27 121.92 0)
		(unit 1)
		(exclude_from_sim no)
		(in_bom yes)
		(on_board yes)
		(dnp no)
		(property "Reference" "#PWR0250"
			(at 264.16 124.46 0)
			(effects
				(font
					(size 1.27 1.27)
					(thickness 0.15)
				)
				(justify left bottom)
				(hide yes)
			)
		)
		(property "Value" "GND"
			(at 255.27 125.73 0)
			(effects
				(font
					(size 1.27 1.27)
					(thickness 0.15)
				)
			)
		)
		(property "Footprint" ""
			(at 264.16 129.54 0)
			(effects
				(font
					(size 1.27 1.27)
					(thickness 0.15)
				)
				(justify left bottom)
				(hide yes)
			)
		)
		(property "Datasheet" ""
			(at 264.16 134.62 0)
			(effects
				(font
					(size 1.27 1.27)
					(thickness 0.15)
				)
				(justify left bottom)
				(hide yes)
			)
		)
		(property "Description" ""
			(at 255.27 121.92 0)
			(effects
				(font
					(size 1.27 1.27)
				)
				(hide yes)
			)
		)
		(property "Author" "Antmicro"
			(at 264.16 129.54 0)
			(effects
				(font
					(size 1.27 1.27)
					(thickness 0.15)
				)
				(justify left bottom)
				(hide yes)
			)
		)
		(property "License" "Apache-2.0"
			(at 264.16 132.08 0)
			(effects
				(font
					(size 1.27 1.27)
					(thickness 0.15)
				)
				(justify left bottom)
				(hide yes)
			)
		)
		(pin "1"
		)
		(instances
			(project "OCuLink to 10GbE adapter"
				(path ""
					(reference "#PWR0250")
					(unit 1)
				)
			)
		)
	)
	(symbol
		(lib_id "antmicroCapacitors0402:C_100n_0402")
		(at 38.1 229.87 90)
		(unit 1)
		(exclude_from_sim no)
		(in_bom yes)
		(on_board yes)
		(dnp no)
		(property "Reference" "C70"
			(at 40.132 226.06 90)
			(effects
				(font
					(size 1.27 1.27)
					(thickness 0.15)
				)
				(justify right)
			)
		)
		(property "Value" "C_100n_0402"
			(at 60.96 214.63 0)
			(effects
				(font
					(size 1.27 1.27)
					(thickness 0.15)
				)
				(justify left bottom)
				(hide yes)
			)
		)
		(property "Footprint" "antmicro-footprints:C_0402_1005Metric"
			(at 63.5 214.63 0)
			(effects
				(font
					(size 1.27 1.27)
					(thickness 0.15)
				)
				(justify left bottom)
				(hide yes)
			)
		)
		(property "Datasheet" "https://www.murata.com/products/productdetail?partno=GRM155R61H104KE14%23"
			(at 66.04 214.63 0)
			(effects
				(font
					(size 1.27 1.27)
					(thickness 0.15)
				)
				(justify left bottom)
				(hide yes)
			)
		)
		(property "Description" "SMD Multilayer Ceramic Capacitor, 0.1 µF, 50 V, 0402 [1005 Metric], ± 10%, X5R, GRM Series"
			(at 38.1 229.87 0)
			(effects
				(font
					(size 1.27 1.27)
				)
				(hide yes)
			)
		)
		(property "MPN" "GRM155R61H104KE14D"
			(at 68.58 214.63 0)
			(effects
				(font
					(size 1.27 1.27)
					(thickness 0.15)
				)
				(justify left bottom)
				(hide yes)
			)
		)
		(property "Val" "100n"
			(at 40.132 228.6 90)
			(effects
				(font
					(size 1.27 1.27)
					(thickness 0.15)
				)
				(justify right)
			)
		)
		(property "Voltage" "50V"
			(at 48.26 214.63 0)
			(effects
				(font
					(size 1.27 1.27)
					(thickness 0.15)
				)
				(justify left bottom)
				(hide yes)
			)
		)
		(property "Dielectric" "X5R"
			(at 50.8 214.63 0)
			(effects
				(font
					(size 1.27 1.27)
					(thickness 0.15)
				)
				(justify left bottom)
				(hide yes)
			)
		)
		(property "Manufacturer" "Murata"
			(at 53.34 214.63 0)
			(effects
				(font
					(size 1.27 1.27)
					(thickness 0.15)
				)
				(justify left bottom)
				(hide yes)
			)
		)
		(property "License" "Apache-2.0"
			(at 55.88 214.63 0)
			(effects
				(font
					(size 1.27 1.27)
					(thickness 0.15)
				)
				(justify left bottom)
				(hide yes)
			)
		)
		(property "Author" "Antmicro"
			(at 58.42 214.63 0)
			(effects
				(font
					(size 1.27 1.27)
					(thickness 0.15)
				)
				(justify left bottom)
				(hide yes)
			)
		)
		(pin "2"
		)
		(pin "1"
		)
		(instances
			(project "OCuLink to 10GbE adapter"
				(path ""
					(reference "C70")
					(unit 1)
				)
			)
		)
	)
	(symbol
		(lib_id "antmicropower:GND")
		(at 100.33 182.88 0)
		(mirror y)
		(unit 1)
		(exclude_from_sim no)
		(in_bom yes)
		(on_board yes)
		(dnp no)
		(property "Reference" "#PWR0312"
			(at 91.44 185.42 0)
			(effects
				(font
					(size 1.27 1.27)
					(thickness 0.15)
				)
				(justify left bottom)
				(hide yes)
			)
		)
		(property "Value" "GND"
			(at 100.33 186.69 0)
			(effects
				(font
					(size 1.27 1.27)
					(thickness 0.15)
				)
			)
		)
		(property "Footprint" ""
			(at 91.44 190.5 0)
			(effects
				(font
					(size 1.27 1.27)
					(thickness 0.15)
				)
				(justify left bottom)
				(hide yes)
			)
		)
		(property "Datasheet" ""
			(at 91.44 195.58 0)
			(effects
				(font
					(size 1.27 1.27)
					(thickness 0.15)
				)
				(justify left bottom)
				(hide yes)
			)
		)
		(property "Description" ""
			(at 100.33 182.88 0)
			(effects
				(font
					(size 1.27 1.27)
				)
				(hide yes)
			)
		)
		(property "Author" "Antmicro"
			(at 91.44 190.5 0)
			(effects
				(font
					(size 1.27 1.27)
					(thickness 0.15)
				)
				(justify left bottom)
				(hide yes)
			)
		)
		(property "License" "Apache-2.0"
			(at 91.44 193.04 0)
			(effects
				(font
					(size 1.27 1.27)
					(thickness 0.15)
				)
				(justify left bottom)
				(hide yes)
			)
		)
		(pin "1"
		)
		(instances
			(project "oculink-to-10gbe-adapter"
				(path ""
					(reference "#PWR0312")
					(unit 1)
				)
			)
		)
	)
	(symbol
		(lib_id "antmicroResistors0402:R_10R_0402")
		(at 105.41 170.18 0)
		(unit 1)
		(exclude_from_sim no)
		(in_bom yes)
		(on_board yes)
		(dnp no)
		(property "Reference" "R68"
			(at 105.41 168.91 0)
			(effects
				(font
					(size 1.27 1.27)
					(thickness 0.15)
				)
				(justify right)
			)
		)
		(property "Value" "R_10R_0402"
			(at 125.73 182.88 0)
			(effects
				(font
					(size 1.27 1.27)
					(thickness 0.15)
				)
				(justify left bottom)
				(hide yes)
			)
		)
		(property "Footprint" "antmicro-footprints:R_0402_1005Metric"
			(at 125.73 185.42 0)
			(effects
				(font
					(size 1.27 1.27)
					(thickness 0.15)
				)
				(justify left bottom)
				(hide yes)
			)
		)
		(property "Datasheet" "https://www.bourns.com/docs/product-datasheets/cr.pdf"
			(at 125.73 187.96 0)
			(effects
				(font
					(size 1.27 1.27)
					(thickness 0.15)
				)
				(justify left bottom)
				(hide yes)
			)
		)
		(property "Description" "SMD Chip Resistor, 10 ohm, ± 1%, 62.5 mW, 0402 [1005 Metric], Thick Film, General Purpose"
			(at 105.41 170.18 0)
			(effects
				(font
					(size 1.27 1.27)
				)
				(hide yes)
			)
		)
		(property "MPN" "CR0402-FX-10R0GLF"
			(at 125.73 190.5 0)
			(effects
				(font
					(size 1.27 1.27)
					(thickness 0.15)
				)
				(justify left bottom)
				(hide yes)
			)
		)
		(property "Manufacturer" "Bourns"
			(at 125.73 193.04 0)
			(effects
				(font
					(size 1.27 1.27)
					(thickness 0.15)
				)
				(justify left bottom)
				(hide yes)
			)
		)
		(property "License" "Apache-2.0"
			(at 125.73 195.58 0)
			(effects
				(font
					(size 1.27 1.27)
					(thickness 0.15)
				)
				(justify left bottom)
				(hide yes)
			)
		)
		(property "Author" "Antmicro"
			(at 125.73 198.12 0)
			(effects
				(font
					(size 1.27 1.27)
					(thickness 0.15)
				)
				(justify left bottom)
				(hide yes)
			)
		)
		(property "Val" "10R"
			(at 110.49 168.91 0)
			(effects
				(font
					(size 1.27 1.27)
					(thickness 0.15)
				)
				(justify left)
			)
		)
		(property "Tolerance" "1%"
			(at 125.73 180.34 0)
			(effects
				(font
					(size 1.27 1.27)
				)
				(justify left bottom)
				(hide yes)
			)
		)
		(pin "2"
		)
		(pin "1"
		)
		(instances
			(project "OCuLink to 10GbE adapter"
				(path ""
					(reference "R68")
					(unit 1)
				)
			)
		)
	)
	(symbol
		(lib_id "antmicroResistors0402:R_22R_0402")
		(at 121.92 223.52 0)
		(unit 1)
		(exclude_from_sim no)
		(in_bom yes)
		(on_board yes)
		(dnp no)
		(property "Reference" "R42"
			(at 121.92 222.504 0)
			(effects
				(font
					(size 1.27 1.27)
					(thickness 0.15)
				)
				(justify right)
			)
		)
		(property "Value" "R_22R_0402"
			(at 142.24 236.22 0)
			(effects
				(font
					(size 1.27 1.27)
					(thickness 0.15)
				)
				(justify left bottom)
				(hide yes)
			)
		)
		(property "Footprint" "antmicro-footprints:R_0402_1005Metric"
			(at 142.24 238.76 0)
			(effects
				(font
					(size 1.27 1.27)
					(thickness 0.15)
				)
				(justify left bottom)
				(hide yes)
			)
		)
		(property "Datasheet" "https://www.bourns.com/docs/product-datasheets/cr.pdf"
			(at 142.24 241.3 0)
			(effects
				(font
					(size 1.27 1.27)
					(thickness 0.15)
				)
				(justify left bottom)
				(hide yes)
			)
		)
		(property "Description" "SMD Chip Resistor, 22 ohm, ± 1%, 62.5 mW, 0402 [1005 Metric], Thick Film, General Purpose"
			(at 121.92 223.52 0)
			(effects
				(font
					(size 1.27 1.27)
				)
				(hide yes)
			)
		)
		(property "MPN" "CR0402-FX-22R0GLF"
			(at 142.24 243.84 0)
			(effects
				(font
					(size 1.27 1.27)
					(thickness 0.15)
				)
				(justify left bottom)
				(hide yes)
			)
		)
		(property "Manufacturer" "Bourns"
			(at 142.24 246.38 0)
			(effects
				(font
					(size 1.27 1.27)
					(thickness 0.15)
				)
				(justify left bottom)
				(hide yes)
			)
		)
		(property "License" "Apache-2.0"
			(at 142.24 248.92 0)
			(effects
				(font
					(size 1.27 1.27)
					(thickness 0.15)
				)
				(justify left bottom)
				(hide yes)
			)
		)
		(property "Author" "Antmicro"
			(at 142.24 251.46 0)
			(effects
				(font
					(size 1.27 1.27)
					(thickness 0.15)
				)
				(justify left bottom)
				(hide yes)
			)
		)
		(property "Val" "22R"
			(at 127.254 222.504 0)
			(effects
				(font
					(size 1.27 1.27)
					(thickness 0.15)
				)
				(justify left)
			)
		)
		(property "Tolerance" "1%"
			(at 142.24 233.68 0)
			(effects
				(font
					(size 1.27 1.27)
				)
				(justify left bottom)
				(hide yes)
			)
		)
		(pin "1"
		)
		(pin "2"
		)
		(instances
			(project "OCuLink to 10GbE adapter"
				(path ""
					(reference "R42")
					(unit 1)
				)
			)
		)
	)
	(symbol
		(lib_id "antmicropower:GND")
		(at 133.35 236.22 0)
		(unit 1)
		(exclude_from_sim no)
		(in_bom yes)
		(on_board yes)
		(dnp no)
		(property "Reference" "#PWR093"
			(at 142.24 238.76 0)
			(effects
				(font
					(size 1.27 1.27)
					(thickness 0.15)
				)
				(justify left bottom)
				(hide yes)
			)
		)
		(property "Value" "GND"
			(at 133.35 240.03 0)
			(effects
				(font
					(size 1.27 1.27)
					(thickness 0.15)
				)
			)
		)
		(property "Footprint" ""
			(at 142.24 243.84 0)
			(effects
				(font
					(size 1.27 1.27)
					(thickness 0.15)
				)
				(justify left bottom)
				(hide yes)
			)
		)
		(property "Datasheet" ""
			(at 142.24 248.92 0)
			(effects
				(font
					(size 1.27 1.27)
					(thickness 0.15)
				)
				(justify left bottom)
				(hide yes)
			)
		)
		(property "Description" ""
			(at 133.35 236.22 0)
			(effects
				(font
					(size 1.27 1.27)
				)
				(hide yes)
			)
		)
		(property "Author" "Antmicro"
			(at 142.24 243.84 0)
			(effects
				(font
					(size 1.27 1.27)
					(thickness 0.15)
				)
				(justify left bottom)
				(hide yes)
			)
		)
		(property "License" "Apache-2.0"
			(at 142.24 246.38 0)
			(effects
				(font
					(size 1.27 1.27)
					(thickness 0.15)
				)
				(justify left bottom)
				(hide yes)
			)
		)
		(pin "1"
		)
		(instances
			(project "OCuLink to 10GbE adapter"
				(path ""
					(reference "#PWR093")
					(unit 1)
				)
			)
		)
	)
	(symbol
		(lib_id "antmicropower:GND")
		(at 175.26 254 0)
		(unit 1)
		(exclude_from_sim no)
		(in_bom yes)
		(on_board yes)
		(dnp no)
		(property "Reference" "#PWR0257"
			(at 184.15 256.54 0)
			(effects
				(font
					(size 1.27 1.27)
					(thickness 0.15)
				)
				(justify left bottom)
				(hide yes)
			)
		)
		(property "Value" "GND"
			(at 175.26 257.81 0)
			(effects
				(font
					(size 1.27 1.27)
					(thickness 0.15)
				)
			)
		)
		(property "Footprint" ""
			(at 184.15 261.62 0)
			(effects
				(font
					(size 1.27 1.27)
					(thickness 0.15)
				)
				(justify left bottom)
				(hide yes)
			)
		)
		(property "Datasheet" ""
			(at 184.15 266.7 0)
			(effects
				(font
					(size 1.27 1.27)
					(thickness 0.15)
				)
				(justify left bottom)
				(hide yes)
			)
		)
		(property "Description" ""
			(at 175.26 254 0)
			(effects
				(font
					(size 1.27 1.27)
				)
				(hide yes)
			)
		)
		(property "Author" "Antmicro"
			(at 184.15 261.62 0)
			(effects
				(font
					(size 1.27 1.27)
					(thickness 0.15)
				)
				(justify left bottom)
				(hide yes)
			)
		)
		(property "License" "Apache-2.0"
			(at 184.15 264.16 0)
			(effects
				(font
					(size 1.27 1.27)
					(thickness 0.15)
				)
				(justify left bottom)
				(hide yes)
			)
		)
		(pin "1"
		)
		(instances
			(project "OCuLink to 10GbE adapter"
				(path ""
					(reference "#PWR0257")
					(unit 1)
				)
			)
		)
	)
	(symbol
		(lib_id "antmicroResistors0402:R_6k04_0.1%_0402")
		(at 264.16 119.38 90)
		(unit 1)
		(exclude_from_sim no)
		(in_bom yes)
		(on_board yes)
		(dnp no)
		(property "Reference" "R58"
			(at 265.684 114.3 90)
			(effects
				(font
					(size 1.27 1.27)
					(thickness 0.15)
				)
				(justify right)
			)
		)
		(property "Value" "R_6k04_0.1%_0402"
			(at 276.86 99.06 0)
			(effects
				(font
					(size 1.27 1.27)
					(thickness 0.15)
				)
				(justify left bottom)
				(hide yes)
			)
		)
		(property "Footprint" "antmicro-footprints:R_0402_1005Metric"
			(at 279.4 99.06 0)
			(effects
				(font
					(size 1.27 1.27)
					(thickness 0.15)
				)
				(justify left bottom)
				(hide yes)
			)
		)
		(property "Datasheet" "https://www.vishay.com/docs/28758/tnpw_e3.pdf"
			(at 281.94 99.06 0)
			(effects
				(font
					(size 1.27 1.27)
					(thickness 0.15)
				)
				(justify left bottom)
				(hide yes)
			)
		)
		(property "Description" "SMD Chip Resistor, 6.49 kohm, ± 1%, 62.5 mW, 0402 [1005 Metric], Thick Film, General Purpose"
			(at 264.16 119.38 0)
			(effects
				(font
					(size 1.27 1.27)
				)
				(hide yes)
			)
		)
		(property "MPN" "TNPW04026K04BEED"
			(at 284.48 99.06 0)
			(effects
				(font
					(size 1.27 1.27)
					(thickness 0.15)
				)
				(justify left bottom)
				(hide yes)
			)
		)
		(property "Manufacturer" "Vishay"
			(at 287.02 99.06 0)
			(effects
				(font
					(size 1.27 1.27)
					(thickness 0.15)
				)
				(justify left bottom)
				(hide yes)
			)
		)
		(property "License" "Apache-2.0"
			(at 289.56 99.06 0)
			(effects
				(font
					(size 1.27 1.27)
					(thickness 0.15)
				)
				(justify left bottom)
				(hide yes)
			)
		)
		(property "Author" "Antmicro"
			(at 292.1 99.06 0)
			(effects
				(font
					(size 1.27 1.27)
					(thickness 0.15)
				)
				(justify left bottom)
				(hide yes)
			)
		)
		(property "Val" "6k04"
			(at 265.684 116.84 90)
			(effects
				(font
					(size 1.27 1.27)
					(thickness 0.15)
				)
				(justify right)
			)
		)
		(property "Tolerance" "0.1%"
			(at 265.684 119.3799 90)
			(effects
				(font
					(size 1.27 1.27)
				)
				(justify right)
			)
		)
		(pin "1"
		)
		(pin "2"
		)
		(instances
			(project "OCuLink to 10GbE adapter"
				(path ""
					(reference "R58")
					(unit 1)
				)
			)
		)
	)
	(symbol
		(lib_id "antmicroFerriteBeadsandChips:FB_330Z_1.5A_Murata-BLM21PG_0805")
		(at 43.18 217.17 0)
		(unit 1)
		(exclude_from_sim no)
		(in_bom yes)
		(on_board yes)
		(dnp no)
		(fields_autoplaced yes)
		(property "Reference" "FB2"
			(at 45.6819 210.82 0)
			(effects
				(font
					(size 1.27 1.27)
					(thickness 0.15)
				)
			)
		)
		(property "Value" "FB_330Z_1.5A_Murata-BLM21PG_0805"
			(at 57.15 219.71 0)
			(effects
				(font
					(size 1.27 1.27)
					(thickness 0.15)
				)
				(justify left bottom)
				(hide yes)
			)
		)
		(property "Footprint" "antmicro-footprints:FB_0805_2012Metric"
			(at 57.15 224.79 0)
			(effects
				(font
					(size 1.27 1.27)
					(thickness 0.15)
				)
				(justify left bottom)
				(hide yes)
			)
		)
		(property "Datasheet" "https://www.murata.com/products/productdata/8796738977822/ENFA0005.pdf?1653276712000"
			(at 57.15 227.33 0)
			(effects
				(font
					(size 1.27 1.27)
					(thickness 0.15)
				)
				(justify left bottom)
				(hide yes)
			)
		)
		(property "Description" "Ferrite Bead, 0805 [2012 Metric], 330 ohm, 1.5 A, BLM21P, 0.07 ohm, ± 25%, DC power line"
			(at 43.18 217.17 0)
			(effects
				(font
					(size 1.27 1.27)
				)
				(hide yes)
			)
		)
		(property "Val" "330Z/1.5A"
			(at 45.6819 213.36 0)
			(effects
				(font
					(size 1.27 1.27)
				)
			)
		)
		(property "MPN" "BLM21PG331SN1D"
			(at 57.15 229.87 0)
			(effects
				(font
					(size 1.27 1.27)
					(thickness 0.15)
				)
				(justify left bottom)
				(hide yes)
			)
		)
		(property "Manufacturer" "Murata"
			(at 57.15 232.41 0)
			(effects
				(font
					(size 1.27 1.27)
					(thickness 0.15)
				)
				(justify left bottom)
				(hide yes)
			)
		)
		(property "Current" ""
			(at 63.5 240.03 0)
			(effects
				(font
					(size 1.27 1.27)
					(thickness 0.15)
				)
				(justify left bottom)
				(hide yes)
			)
		)
		(property "Author" "Antmicro"
			(at 57.15 234.95 0)
			(effects
				(font
					(size 1.27 1.27)
					(thickness 0.15)
				)
				(justify left bottom)
				(hide yes)
			)
		)
		(property "License" "Apache-2.0"
			(at 57.15 237.49 0)
			(effects
				(font
					(size 1.27 1.27)
					(thickness 0.15)
				)
				(justify left bottom)
				(hide yes)
			)
		)
		(pin "1"
		)
		(pin "2"
		)
		(instances
			(project "OCuLink to 10GbE adapter"
				(path ""
					(reference "FB2")
					(unit 1)
				)
			)
		)
	)
	(symbol
		(lib_id "antmicroInterfaceControllers:EZX710AT2_S_LMR5")
		(at 193.04 53.34 0)
		(unit 2)
		(exclude_from_sim no)
		(in_bom yes)
		(on_board yes)
		(dnp no)
		(fields_autoplaced yes)
		(property "Reference" "U9"
			(at 213.36 45.72 0)
			(effects
				(font
					(size 1.27 1.27)
					(thickness 0.15)
				)
			)
		)
		(property "Value" "EZX710AT2_S_LMR5"
			(at 269.24 58.42 0)
			(effects
				(font
					(size 1.27 1.27)
					(thickness 0.15)
				)
				(justify left bottom)
				(hide yes)
			)
		)
		(property "Footprint" "antmicro-footprints:FCBGA-503_22x22mm_Layout21x24_P1mm"
			(at 269.24 60.96 0)
			(effects
				(font
					(size 1.27 1.27)
					(thickness 0.15)
				)
				(justify left bottom)
				(hide yes)
			)
		)
		(property "Datasheet" "https://www.google.com/url?sa=t&source=web&rct=j&opi=89978449&url=https://cdrdv2-public.intel.com/596333/596333_X710-TM4_Datasheet_v_2_4.pdf&ved=2ahUKEwiSuv20_sCOAxXVCRAIHdxGO_UQFnoECBEQAQ&usg=AOvVaw1CjGyrGWE8ZvOdw4VBsY6U"
			(at 269.24 63.5 0)
			(effects
				(font
					(size 1.27 1.27)
					(thickness 0.15)
				)
				(justify left bottom)
				(hide yes)
			)
		)
		(property "Description" "Ethernet ICs Intel Ethernet Controller 10 Gigabit X7"
			(at 269.24 66.04 0)
			(effects
				(font
					(size 1.27 1.27)
					(thickness 0.15)
				)
				(justify left bottom)
				(hide yes)
			)
		)
		(property "MPN" "EZX710AT2 S LMR5"
			(at 213.36 48.26 0)
			(effects
				(font
					(size 1.27 1.27)
					(thickness 0.15)
				)
			)
		)
		(property "Manufacturer" "Intel"
			(at 269.24 68.58 0)
			(effects
				(font
					(size 1.27 1.27)
					(thickness 0.15)
				)
				(justify left bottom)
				(hide yes)
			)
		)
		(property "Author" "Antmicro"
			(at 269.24 71.12 0)
			(effects
				(font
					(size 1.27 1.27)
					(thickness 0.15)
				)
				(justify left bottom)
				(hide yes)
			)
		)
		(property "License" "Apache-2.0"
			(at 269.24 73.66 0)
			(effects
				(font
					(size 1.27 1.27)
					(thickness 0.15)
				)
				(justify left bottom)
				(hide yes)
			)
		)
		(pin "E39"
		)
		(pin "AD18"
		)
		(pin "AD2"
		)
		(pin "K32"
		)
		(pin "M32"
		)
		(pin "M30"
		)
		(pin "D8"
		)
		(pin "G23"
		)
		(pin "D4"
		)
		(pin "P16"
		)
		(pin "P18"
		)
		(pin "P20"
		)
		(pin "K40"
		)
		(pin "T20"
		)
		(pin "AC31"
		)
		(pin "E5"
		)
		(pin "AD10"
		)
		(pin "W1"
		)
		(pin "G41"
		)
		(pin "W3"
		)
		(pin "U1"
		)
		(pin "H42"
		)
		(pin "H38"
		)
		(pin "K10"
		)
		(pin "U31"
		)
		(pin "V32"
		)
		(pin "C21"
		)
		(pin "B42"
		)
		(pin "V24"
		)
		(pin "P24"
		)
		(pin "Y16"
		)
		(pin "D14"
		)
		(pin "L25"
		)
		(pin "E13"
		)
		(pin "P26"
		)
		(pin "B6"
		)
		(pin "R41"
		)
		(pin "AB32"
		)
		(pin "AB34"
		)
		(pin "R5"
		)
		(pin "T26"
		)
		(pin "AA19"
		)
		(pin "AA21"
		)
		(pin "L37"
		)
		(pin "H2"
		)
		(pin "F22"
		)
		(pin "E19"
		)
		(pin "A17"
		)
		(pin "G19"
		)
		(pin "G21"
		)
		(pin "H34"
		)
		(pin "H36"
		)
		(pin "A15"
		)
		(pin "A19"
		)
		(pin "R39"
		)
		(pin "W37"
		)
		(pin "W39"
		)
		(pin "Y14"
		)
		(pin "L5"
		)
		(pin "N3"
		)
		(pin "N1"
		)
		(pin "T4"
		)
		(pin "B18"
		)
		(pin "W31"
		)
		(pin "W33"
		)
		(pin "W35"
		)
		(pin "W41"
		)
		(pin "C19"
		)
		(pin "C5"
		)
		(pin "M42"
		)
		(pin "G37"
		)
		(pin "L39"
		)
		(pin "F4"
		)
		(pin "AD20"
		)
		(pin "G7"
		)
		(pin "T40"
		)
		(pin "J9"
		)
		(pin "AB18"
		)
		(pin "AA35"
		)
		(pin "H6"
		)
		(pin "M8"
		)
		(pin "A39"
		)
		(pin "P28"
		)
		(pin "Y30"
		)
		(pin "G5"
		)
		(pin "AD32"
		)
		(pin "AD8"
		)
		(pin "AB28"
		)
		(pin "H18"
		)
		(pin "H20"
		)
		(pin "J15"
		)
		(pin "H16"
		)
		(pin "P22"
		)
		(pin "M6"
		)
		(pin "E9"
		)
		(pin "H24"
		)
		(pin "K34"
		)
		(pin "K36"
		)
		(pin "K26"
		)
		(pin "B36"
		)
		(pin "C3"
		)
		(pin "AD22"
		)
		(pin "AA27"
		)
		(pin "V4"
		)
		(pin "B38"
		)
		(pin "D42"
		)
		(pin "F12"
		)
		(pin "AB16"
		)
		(pin "K8"
		)
		(pin "M10"
		)
		(pin "H14"
		)
		(pin "G13"
		)
		(pin "H30"
		)
		(pin "H32"
		)
		(pin "B24"
		)
		(pin "L23"
		)
		(pin "A33"
		)
		(pin "AC25"
		)
		(pin "AC27"
		)
		(pin "P32"
		)
		(pin "P30"
		)
		(pin "H4"
		)
		(pin "U25"
		)
		(pin "V12"
		)
		(pin "V14"
		)
		(pin "V16"
		)
		(pin "W9"
		)
		(pin "T8"
		)
		(pin "AA39"
		)
		(pin "M4"
		)
		(pin "AD24"
		)
		(pin "AD30"
		)
		(pin "U5"
		)
		(pin "U7"
		)
		(pin "AA41"
		)
		(pin "AA9"
		)
		(pin "E17"
		)
		(pin "V36"
		)
		(pin "T42"
		)
		(pin "U27"
		)
		(pin "F16"
		)
		(pin "A23"
		)
		(pin "Y18"
		)
		(pin "V2"
		)
		(pin "V8"
		)
		(pin "L35"
		)
		(pin "H40"
		)
		(pin "N5"
		)
		(pin "AA31"
		)
		(pin "C11"
		)
		(pin "C13"
		)
		(pin "B12"
		)
		(pin "B16"
		)
		(pin "P8"
		)
		(pin "A35"
		)
		(pin "T24"
		)
		(pin "Y38"
		)
		(pin "AC39"
		)
		(pin "J3"
		)
		(pin "U9"
		)
		(pin "K24"
		)
		(pin "AD40"
		)
		(pin "C1"
		)
		(pin "L13"
		)
		(pin "L15"
		)
		(pin "F8"
		)
		(pin "F6"
		)
		(pin "AA7"
		)
		(pin "W25"
		)
		(pin "V42"
		)
		(pin "N7"
		)
		(pin "R9"
		)
		(pin "Y2"
		)
		(pin "F24"
		)
		(pin "F26"
		)
		(pin "C35"
		)
		(pin "C37"
		)
		(pin "J25"
		)
		(pin "AC21"
		)
		(pin "AC23"
		)
		(pin "P42"
		)
		(pin "E11"
		)
		(pin "Y12"
		)
		(pin "A5"
		)
		(pin "V38"
		)
		(pin "AB12"
		)
		(pin "AB4"
		)
		(pin "AB40"
		)
		(pin "AD42"
		)
		(pin "AD6"
		)
		(pin "D10"
		)
		(pin "D2"
		)
		(pin "R23"
		)
		(pin "Y24"
		)
		(pin "T38"
		)
		(pin "AD14"
		)
		(pin "AC41"
		)
		(pin "AC7"
		)
		(pin "Y10"
		)
		(pin "U13"
		)
		(pin "U15"
		)
		(pin "W17"
		)
		(pin "W19"
		)
		(pin "W27"
		)
		(pin "M2"
		)
		(pin "L17"
		)
		(pin "N11"
		)
		(pin "H12"
		)
		(pin "B14"
		)
		(pin "G27"
		)
		(pin "G29"
		)
		(pin "K6"
		)
		(pin "AB42"
		)
		(pin "M24"
		)
		(pin "E7"
		)
		(pin "AC17"
		)
		(pin "AC19"
		)
		(pin "R31"
		)
		(pin "R29"
		)
		(pin "A31"
		)
		(pin "B22"
		)
		(pin "B32"
		)
		(pin "Y36"
		)
		(pin "Y4"
		)
		(pin "Y40"
		)
		(pin "R35"
		)
		(pin "T10"
		)
		(pin "T12"
		)
		(pin "J1"
		)
		(pin "V6"
		)
		(pin "A13"
		)
		(pin "W21"
		)
		(pin "L19"
		)
		(pin "Y6"
		)
		(pin "Y8"
		)
		(pin "A21"
		)
		(pin "G35"
		)
		(pin "G25"
		)
		(pin "C25"
		)
		(pin "C27"
		)
		(pin "J17"
		)
		(pin "K30"
		)
		(pin "W23"
		)
		(pin "M12"
		)
		(pin "M14"
		)
		(pin "M16"
		)
		(pin "D18"
		)
		(pin "K42"
		)
		(pin "T14"
		)
		(pin "T16"
		)
		(pin "T18"
		)
		(pin "T28"
		)
		(pin "U39"
		)
		(pin "N39"
		)
		(pin "U17"
		)
		(pin "U19"
		)
		(pin "R11"
		)
		(pin "T34"
		)
		(pin "P38"
		)
		(pin "E1"
		)
		(pin "C7"
		)
		(pin "C9"
		)
		(pin "F2"
		)
		(pin "J29"
		)
		(pin "J31"
		)
		(pin "U37"
		)
		(pin "AC9"
		)
		(pin "AD12"
		)
		(pin "P40"
		)
		(pin "K4"
		)
		(pin "N9"
		)
		(pin "M40"
		)
		(pin "E3"
		)
		(pin "F18"
		)
		(pin "F20"
		)
		(pin "T6"
		)
		(pin "U3"
		)
		(pin "C29"
		)
		(pin "J27"
		)
		(pin "AB26"
		)
		(pin "AB30"
		)
		(pin "AB2"
		)
		(pin "AA1"
		)
		(pin "P2"
		)
		(pin "R1"
		)
		(pin "R33"
		)
		(pin "AC1"
		)
		(pin "AC11"
		)
		(pin "AA5"
		)
		(pin "AC5"
		)
		(pin "AD4"
		)
		(pin "U41"
		)
		(pin "N19"
		)
		(pin "N21"
		)
		(pin "R37"
		)
		(pin "W5"
		)
		(pin "E25"
		)
		(pin "D22"
		)
		(pin "U29"
		)
		(pin "E29"
		)
		(pin "C33"
		)
		(pin "N33"
		)
		(pin "F14"
		)
		(pin "A29"
		)
		(pin "N35"
		)
		(pin "B34"
		)
		(pin "Y20"
		)
		(pin "AC29"
		)
		(pin "AC3"
		)
		(pin "U21"
		)
		(pin "W11"
		)
		(pin "U23"
		)
		(pin "N41"
		)
		(pin "P4"
		)
		(pin "AC35"
		)
		(pin "AD34"
		)
		(pin "AD38"
		)
		(pin "G39"
		)
		(pin "L11"
		)
		(pin "G11"
		)
		(pin "V26"
		)
		(pin "G31"
		)
		(pin "G33"
		)
		(pin "G9"
		)
		(pin "AA23"
		)
		(pin "AA25"
		)
		(pin "G15"
		)
		(pin "K2"
		)
		(pin "U35"
		)
		(pin "U33"
		)
		(pin "J23"
		)
		(pin "R3"
		)
		(pin "B2"
		)
		(pin "B20"
		)
		(pin "P34"
		)
		(pin "E37"
		)
		(pin "E27"
		)
		(pin "J7"
		)
		(pin "H10"
		)
		(pin "J5"
		)
		(pin "AD16"
		)
		(pin "M26"
		)
		(pin "D12"
		)
		(pin "C15"
		)
		(pin "C17"
		)
		(pin "L41"
		)
		(pin "B40"
		)
		(pin "E41"
		)
		(pin "B4"
		)
		(pin "B8"
		)
		(pin "K28"
		)
		(pin "D20"
		)
		(pin "L33"
		)
		(pin "AB24"
		)
		(pin "AC13"
		)
		(pin "AC15"
		)
		(pin "E21"
		)
		(pin "E23"
		)
		(pin "L3"
		)
		(pin "R7"
		)
		(pin "V40"
		)
		(pin "E33"
		)
		(pin "F40"
		)
		(pin "F42"
		)
		(pin "G3"
		)
		(pin "AA15"
		)
		(pin "AA17"
		)
		(pin "M22"
		)
		(pin "W7"
		)
		(pin "AD26"
		)
		(pin "J35"
		)
		(pin "J33"
		)
		(pin "M28"
		)
		(pin "F34"
		)
		(pin "F36"
		)
		(pin "K18"
		)
		(pin "N27"
		)
		(pin "V34"
		)
		(pin "L7"
		)
		(pin "M36"
		)
		(pin "D26"
		)
		(pin "D28"
		)
		(pin "D36"
		)
		(pin "D38"
		)
		(pin "D40"
		)
		(pin "E31"
		)
		(pin "L9"
		)
		(pin "T2"
		)
		(pin "A9"
		)
		(pin "Y26"
		)
		(pin "Y28"
		)
		(pin "Y32"
		)
		(pin "D6"
		)
		(pin "F38"
		)
		(pin "B10"
		)
		(pin "AA11"
		)
		(pin "AA13"
		)
		(pin "R21"
		)
		(pin "U11"
		)
		(pin "AA29"
		)
		(pin "AA3"
		)
		(pin "H26"
		)
		(pin "H28"
		)
		(pin "K12"
		)
		(pin "K14"
		)
		(pin "AB14"
		)
		(pin "AB20"
		)
		(pin "N23"
		)
		(pin "V10"
		)
		(pin "A11"
		)
		(pin "G1"
		)
		(pin "AB36"
		)
		(pin "AB38"
		)
		(pin "P36"
		)
		(pin "M38"
		)
		(pin "D34"
		)
		(pin "B28"
		)
		(pin "C39"
		)
		(pin "C23"
		)
		(pin "J11"
		)
		(pin "AB22"
		)
		(pin "T22"
		)
		(pin "V30"
		)
		(pin "L31"
		)
		(pin "J13"
		)
		(pin "N25"
		)
		(pin "N31"
		)
		(pin "N29"
		)
		(pin "H22"
		)
		(pin "G17"
		)
		(pin "N37"
		)
		(pin "AD36"
		)
		(pin "A27"
		)
		(pin "F10"
		)
		(pin "AD28"
		)
		(pin "L1"
		)
		(pin "E15"
		)
		(pin "A25"
		)
		(pin "L21"
		)
		(pin "N17"
		)
		(pin "A41"
		)
		(pin "L29"
		)
		(pin "A3"
		)
		(pin "A7"
		)
		(pin "T32"
		)
		(pin "T30"
		)
		(pin "P10"
		)
		(pin "P12"
		)
		(pin "P14"
		)
		(pin "J37"
		)
		(pin "M34"
		)
		(pin "R17"
		)
		(pin "R19"
		)
		(pin "N13"
		)
		(pin "N15"
		)
		(pin "R27"
		)
		(pin "J41"
		)
		(pin "D16"
		)
		(pin "D30"
		)
		(pin "E35"
		)
		(pin "B26"
		)
		(pin "F28"
		)
		(pin "F30"
		)
		(pin "F32"
		)
		(pin "J19"
		)
		(pin "J21"
		)
		(pin "K20"
		)
		(pin "M18"
		)
		(pin "M20"
		)
		(pin "W13"
		)
		(pin "W15"
		)
		(pin "AB10"
		)
		(pin "P6"
		)
		(pin "R25"
		)
		(pin "V22"
		)
		(pin "V18"
		)
		(pin "V20"
		)
		(pin "W29"
		)
		(pin "K22"
		)
		(pin "Y22"
		)
		(pin "AC33"
		)
		(pin "AC37"
		)
		(pin "Y42"
		)
		(pin "R13"
		)
		(pin "R15"
		)
		(pin "H8"
		)
		(pin "Y34"
		)
		(pin "T36"
		)
		(pin "V28"
		)
		(pin "AB6"
		)
		(pin "AB8"
		)
		(pin "D32"
		)
		(pin "J39"
		)
		(pin "L27"
		)
		(pin "C31"
		)
		(pin "C41"
		)
		(pin "D24"
		)
		(pin "K16"
		)
		(pin "K38"
		)
		(pin "B30"
		)
		(pin "AA33"
		)
		(pin "AA37"
		)
		(pin "A37"
		)
		(instances
			(project ""
				(path ""
					(reference "U9")
					(unit 2)
				)
			)
		)
	)
	(symbol
		(lib_id "antmicroResistors0402:R_0R_0402")
		(at 261.62 238.76 90)
		(unit 1)
		(exclude_from_sim no)
		(in_bom yes)
		(on_board yes)
		(dnp no)
		(property "Reference" "R75"
			(at 263.144 234.95 90)
			(effects
				(font
					(size 1.27 1.27)
					(thickness 0.15)
				)
				(justify right)
			)
		)
		(property "Value" "R_0R_0402"
			(at 274.32 218.44 0)
			(effects
				(font
					(size 1.27 1.27)
					(thickness 0.15)
				)
				(justify left bottom)
				(hide yes)
			)
		)
		(property "Footprint" "antmicro-footprints:R_0402_1005Metric"
			(at 276.86 218.44 0)
			(effects
				(font
					(size 1.27 1.27)
					(thickness 0.15)
				)
				(justify left bottom)
				(hide yes)
			)
		)
		(property "Datasheet" "https://industrial.panasonic.com/cdbs/www-data/pdf/RDA0000/AOA0000C301.pdf"
			(at 279.4 218.44 0)
			(effects
				(font
					(size 1.27 1.27)
					(thickness 0.15)
				)
				(justify left bottom)
				(hide yes)
			)
		)
		(property "Description" "SMD Chip Resistor, Jumper, 0 ohm, 100 mW, 0402 [1005 Metric], Thick Film, General Purpose"
			(at 261.62 238.76 0)
			(effects
				(font
					(size 1.27 1.27)
				)
				(hide yes)
			)
		)
		(property "MPN" "ERJ2GE0R00X"
			(at 281.94 218.44 0)
			(effects
				(font
					(size 1.27 1.27)
					(thickness 0.15)
				)
				(justify left bottom)
				(hide yes)
			)
		)
		(property "Manufacturer" "Panasonic"
			(at 284.48 218.44 0)
			(effects
				(font
					(size 1.27 1.27)
					(thickness 0.15)
				)
				(justify left bottom)
				(hide yes)
			)
		)
		(property "License" "Apache-2.0"
			(at 287.02 218.44 0)
			(effects
				(font
					(size 1.27 1.27)
					(thickness 0.15)
				)
				(justify left bottom)
				(hide yes)
			)
		)
		(property "Author" "Antmicro"
			(at 289.56 218.44 0)
			(effects
				(font
					(size 1.27 1.27)
					(thickness 0.15)
				)
				(justify left bottom)
				(hide yes)
			)
		)
		(property "Val" "0R"
			(at 263.144 237.49 90)
			(effects
				(font
					(size 1.27 1.27)
					(thickness 0.15)
				)
				(justify right)
			)
		)
		(property "Tolerance" "~"
			(at 271.78 218.44 0)
			(effects
				(font
					(size 1.27 1.27)
				)
				(justify left bottom)
				(hide yes)
			)
		)
		(property "Current" "1A"
			(at 292.1 218.44 0)
			(effects
				(font
					(size 1.27 1.27)
					(thickness 0.15)
				)
				(justify left bottom)
				(hide yes)
			)
		)
		(pin "1"
		)
		(pin "2"
		)
		(instances
			(project "OCuLink to 10GbE adapter"
				(path ""
					(reference "R75")
					(unit 1)
				)
			)
		)
	)
	(symbol
		(lib_id "antmicroOscillators:Oscillator_25MHz_511ABA25M0000BAGR")
		(at 81.28 223.52 0)
		(unit 1)
		(exclude_from_sim no)
		(in_bom yes)
		(on_board yes)
		(dnp no)
		(fields_autoplaced yes)
		(property "Reference" "Y1"
			(at 90.805 213.36 0)
			(effects
				(font
					(size 1.27 1.27)
					(thickness 0.15)
				)
			)
		)
		(property "Value" "Oscillator_25MHz_511ABA25M0000BAGR"
			(at 109.855 235.585 0)
			(effects
				(font
					(size 1.27 1.27)
					(thickness 0.15)
				)
				(justify left bottom)
				(hide yes)
			)
		)
		(property "Footprint" "antmicro-footprints:Oscillator_SMD_Skyworks_SI511_5x3.2x1.17mm"
			(at 109.855 238.125 0)
			(effects
				(font
					(size 1.27 1.27)
					(thickness 0.15)
				)
				(justify left bottom)
				(hide yes)
			)
		)
		(property "Datasheet" "https://www.mouser.com/datasheet/2/472/si510_11-2507765.pdf"
			(at 109.855 240.665 0)
			(effects
				(font
					(size 1.27 1.27)
					(thickness 0.15)
				)
				(justify left bottom)
				(hide yes)
			)
		)
		(property "Description" "25 MHz XO (Standard) LVPECL Oscillator 3.3V Enable/Disable 6-SMD, No Lead"
			(at 81.28 223.52 0)
			(effects
				(font
					(size 1.27 1.27)
				)
				(hide yes)
			)
		)
		(property "Manufacturer" "Skyworks Solutions"
			(at 109.855 227.965 0)
			(effects
				(font
					(size 1.27 1.27)
					(thickness 0.15)
				)
				(justify left bottom)
				(hide yes)
			)
		)
		(property "MPN" "511ABA25M0000BAGR"
			(at 90.805 215.9 0)
			(effects
				(font
					(size 1.27 1.27)
					(thickness 0.15)
				)
			)
		)
		(property "Val" "25 MHz"
			(at 90.805 218.44 0)
			(effects
				(font
					(size 1.27 1.27)
					(thickness 0.15)
				)
			)
		)
		(property "Author" "Antmicro"
			(at 109.855 243.205 0)
			(effects
				(font
					(size 1.27 1.27)
					(thickness 0.15)
				)
				(justify left bottom)
				(hide yes)
			)
		)
		(property "License" "Apache-2.0"
			(at 109.855 245.745 0)
			(effects
				(font
					(size 1.27 1.27)
					(thickness 0.15)
				)
				(justify left bottom)
				(hide yes)
			)
		)
		(pin "4"
		)
		(pin "5"
		)
		(pin "6"
		)
		(pin "3"
		)
		(pin "2"
		)
		(pin "1"
		)
		(instances
			(project "OCuLink to 10GbE adapter"
				(path ""
					(reference "Y1")
					(unit 1)
				)
			)
		)
	)
	(symbol
		(lib_id "antmicroResistors0402:R_22R_0402")
		(at 121.92 226.06 0)
		(unit 1)
		(exclude_from_sim no)
		(in_bom yes)
		(on_board yes)
		(dnp no)
		(property "Reference" "R44"
			(at 121.92 225.044 0)
			(effects
				(font
					(size 1.27 1.27)
					(thickness 0.15)
				)
				(justify right)
			)
		)
		(property "Value" "R_22R_0402"
			(at 142.24 238.76 0)
			(effects
				(font
					(size 1.27 1.27)
					(thickness 0.15)
				)
				(justify left bottom)
				(hide yes)
			)
		)
		(property "Footprint" "antmicro-footprints:R_0402_1005Metric"
			(at 142.24 241.3 0)
			(effects
				(font
					(size 1.27 1.27)
					(thickness 0.15)
				)
				(justify left bottom)
				(hide yes)
			)
		)
		(property "Datasheet" "https://www.bourns.com/docs/product-datasheets/cr.pdf"
			(at 142.24 243.84 0)
			(effects
				(font
					(size 1.27 1.27)
					(thickness 0.15)
				)
				(justify left bottom)
				(hide yes)
			)
		)
		(property "Description" "SMD Chip Resistor, 22 ohm, ± 1%, 62.5 mW, 0402 [1005 Metric], Thick Film, General Purpose"
			(at 121.92 226.06 0)
			(effects
				(font
					(size 1.27 1.27)
				)
				(hide yes)
			)
		)
		(property "MPN" "CR0402-FX-22R0GLF"
			(at 142.24 246.38 0)
			(effects
				(font
					(size 1.27 1.27)
					(thickness 0.15)
				)
				(justify left bottom)
				(hide yes)
			)
		)
		(property "Manufacturer" "Bourns"
			(at 142.24 248.92 0)
			(effects
				(font
					(size 1.27 1.27)
					(thickness 0.15)
				)
				(justify left bottom)
				(hide yes)
			)
		)
		(property "License" "Apache-2.0"
			(at 142.24 251.46 0)
			(effects
				(font
					(size 1.27 1.27)
					(thickness 0.15)
				)
				(justify left bottom)
				(hide yes)
			)
		)
		(property "Author" "Antmicro"
			(at 142.24 254 0)
			(effects
				(font
					(size 1.27 1.27)
					(thickness 0.15)
				)
				(justify left bottom)
				(hide yes)
			)
		)
		(property "Val" "22R"
			(at 127.254 225.044 0)
			(effects
				(font
					(size 1.27 1.27)
					(thickness 0.15)
				)
				(justify left)
			)
		)
		(property "Tolerance" "1%"
			(at 142.24 236.22 0)
			(effects
				(font
					(size 1.27 1.27)
				)
				(justify left bottom)
				(hide yes)
			)
		)
		(pin "1"
		)
		(pin "2"
		)
		(instances
			(project "OCuLink to 10GbE adapter"
				(path ""
					(reference "R44")
					(unit 1)
				)
			)
		)
	)
	(symbol
		(lib_id "antmicroResistors0402:R_100R_0402")
		(at 175.26 251.46 90)
		(unit 1)
		(exclude_from_sim no)
		(in_bom no)
		(on_board yes)
		(dnp yes)
		(property "Reference" "R77"
			(at 176.784 247.65 90)
			(effects
				(font
					(size 1.27 1.27)
					(thickness 0.15)
				)
				(justify right)
			)
		)
		(property "Value" "R_100R_0402"
			(at 187.96 231.14 0)
			(effects
				(font
					(size 1.27 1.27)
					(thickness 0.15)
				)
				(justify left bottom)
				(hide yes)
			)
		)
		(property "Footprint" "antmicro-footprints:R_0402_1005Metric"
			(at 190.5 231.14 0)
			(effects
				(font
					(size 1.27 1.27)
					(thickness 0.15)
				)
				(justify left bottom)
				(hide yes)
			)
		)
		(property "Datasheet" "https://www.bourns.com/docs/product-datasheets/cr.pdf"
			(at 193.04 231.14 0)
			(effects
				(font
					(size 1.27 1.27)
					(thickness 0.15)
				)
				(justify left bottom)
				(hide yes)
			)
		)
		(property "Description" "SMD Chip Resistor, 100 ohm, ± 1%, 62.5 mW, 0402 [1005 Metric], Thick Film, General Purpose"
			(at 175.26 251.46 0)
			(effects
				(font
					(size 1.27 1.27)
				)
				(hide yes)
			)
		)
		(property "MPN" "CR0402-FX-1000GLF"
			(at 195.58 231.14 0)
			(effects
				(font
					(size 1.27 1.27)
					(thickness 0.15)
				)
				(justify left bottom)
				(hide yes)
			)
		)
		(property "Manufacturer" "Bourns"
			(at 198.12 231.14 0)
			(effects
				(font
					(size 1.27 1.27)
					(thickness 0.15)
				)
				(justify left bottom)
				(hide yes)
			)
		)
		(property "License" "Apache-2.0"
			(at 200.66 231.14 0)
			(effects
				(font
					(size 1.27 1.27)
					(thickness 0.15)
				)
				(justify left bottom)
				(hide yes)
			)
		)
		(property "Author" "Antmicro"
			(at 203.2 231.14 0)
			(effects
				(font
					(size 1.27 1.27)
					(thickness 0.15)
				)
				(justify left bottom)
				(hide yes)
			)
		)
		(property "Val" "100R"
			(at 176.784 250.19 90)
			(effects
				(font
					(size 1.27 1.27)
					(thickness 0.15)
				)
				(justify right)
			)
		)
		(property "Tolerance" "1%"
			(at 185.42 231.14 0)
			(effects
				(font
					(size 1.27 1.27)
				)
				(justify left bottom)
				(hide yes)
			)
		)
		(pin "2"
		)
		(pin "1"
		)
		(instances
			(project ""
				(path ""
					(reference "R77")
					(unit 1)
				)
			)
		)
	)
	(symbol
		(lib_id "antmicropower:+1V8")
		(at 261.62 215.9 0)
		(unit 1)
		(exclude_from_sim no)
		(in_bom yes)
		(on_board yes)
		(dnp no)
		(property "Reference" "#PWR0253"
			(at 276.86 218.44 0)
			(effects
				(font
					(size 1.27 1.27)
					(thickness 0.15)
				)
				(justify left bottom)
				(hide yes)
			)
		)
		(property "Value" "+1V88"
			(at 261.62 212.09 0)
			(effects
				(font
					(size 1.27 1.27)
					(thickness 0.15)
				)
			)
		)
		(property "Footprint" ""
			(at 276.86 223.52 0)
			(effects
				(font
					(size 1.27 1.27)
					(thickness 0.15)
				)
				(justify left bottom)
				(hide yes)
			)
		)
		(property "Datasheet" ""
			(at 276.86 226.06 0)
			(effects
				(font
					(size 1.27 1.27)
					(thickness 0.15)
				)
				(justify left bottom)
				(hide yes)
			)
		)
		(property "Description" ""
			(at 261.62 215.9 0)
			(effects
				(font
					(size 1.27 1.27)
				)
				(hide yes)
			)
		)
		(property "Author" "Antmicro"
			(at 276.86 220.98 0)
			(effects
				(font
					(size 1.27 1.27)
					(thickness 0.15)
				)
				(justify left bottom)
				(hide yes)
			)
		)
		(property "License" "Apache-2.0"
			(at 276.86 223.52 0)
			(effects
				(font
					(size 1.27 1.27)
					(thickness 0.15)
				)
				(justify left bottom)
				(hide yes)
			)
		)
		(pin "1"
		)
		(instances
			(project "OCuLink to 10GbE adapter"
				(path ""
					(reference "#PWR0253")
					(unit 1)
				)
			)
		)
	)
	(symbol
		(lib_id "antmicroResistors0402:R_10R_0402")
		(at 105.41 167.64 0)
		(unit 1)
		(exclude_from_sim no)
		(in_bom yes)
		(on_board yes)
		(dnp no)
		(property "Reference" "R67"
			(at 105.41 166.37 0)
			(effects
				(font
					(size 1.27 1.27)
					(thickness 0.15)
				)
				(justify right)
			)
		)
		(property "Value" "R_10R_0402"
			(at 125.73 180.34 0)
			(effects
				(font
					(size 1.27 1.27)
					(thickness 0.15)
				)
				(justify left bottom)
				(hide yes)
			)
		)
		(property "Footprint" "antmicro-footprints:R_0402_1005Metric"
			(at 125.73 182.88 0)
			(effects
				(font
					(size 1.27 1.27)
					(thickness 0.15)
				)
				(justify left bottom)
				(hide yes)
			)
		)
		(property "Datasheet" "https://www.bourns.com/docs/product-datasheets/cr.pdf"
			(at 125.73 185.42 0)
			(effects
				(font
					(size 1.27 1.27)
					(thickness 0.15)
				)
				(justify left bottom)
				(hide yes)
			)
		)
		(property "Description" "SMD Chip Resistor, 10 ohm, ± 1%, 62.5 mW, 0402 [1005 Metric], Thick Film, General Purpose"
			(at 105.41 167.64 0)
			(effects
				(font
					(size 1.27 1.27)
				)
				(hide yes)
			)
		)
		(property "MPN" "CR0402-FX-10R0GLF"
			(at 125.73 187.96 0)
			(effects
				(font
					(size 1.27 1.27)
					(thickness 0.15)
				)
				(justify left bottom)
				(hide yes)
			)
		)
		(property "Manufacturer" "Bourns"
			(at 125.73 190.5 0)
			(effects
				(font
					(size 1.27 1.27)
					(thickness 0.15)
				)
				(justify left bottom)
				(hide yes)
			)
		)
		(property "License" "Apache-2.0"
			(at 125.73 193.04 0)
			(effects
				(font
					(size 1.27 1.27)
					(thickness 0.15)
				)
				(justify left bottom)
				(hide yes)
			)
		)
		(property "Author" "Antmicro"
			(at 125.73 195.58 0)
			(effects
				(font
					(size 1.27 1.27)
					(thickness 0.15)
				)
				(justify left bottom)
				(hide yes)
			)
		)
		(property "Val" "10R"
			(at 110.49 166.37 0)
			(effects
				(font
					(size 1.27 1.27)
					(thickness 0.15)
				)
				(justify left)
			)
		)
		(property "Tolerance" "1%"
			(at 125.73 177.8 0)
			(effects
				(font
					(size 1.27 1.27)
				)
				(justify left bottom)
				(hide yes)
			)
		)
		(pin "2"
		)
		(pin "1"
		)
		(instances
			(project ""
				(path ""
					(reference "R67")
					(unit 1)
				)
			)
		)
	)
	(symbol
		(lib_id "antmicroResistors0402:R_3k3_0402")
		(at 144.78 165.1 90)
		(unit 1)
		(exclude_from_sim no)
		(in_bom yes)
		(on_board yes)
		(dnp no)
		(property "Reference" "R62"
			(at 146.304 161.29 90)
			(effects
				(font
					(size 1.27 1.27)
					(thickness 0.15)
				)
				(justify right)
			)
		)
		(property "Value" "R_3k3_0402"
			(at 157.48 144.78 0)
			(effects
				(font
					(size 1.27 1.27)
					(thickness 0.15)
				)
				(justify left bottom)
				(hide yes)
			)
		)
		(property "Footprint" "antmicro-footprints:R_0402_1005Metric"
			(at 160.02 144.78 0)
			(effects
				(font
					(size 1.27 1.27)
					(thickness 0.15)
				)
				(justify left bottom)
				(hide yes)
			)
		)
		(property "Datasheet" "https://www.bourns.com/docs/product-datasheets/cr.pdf"
			(at 162.56 144.78 0)
			(effects
				(font
					(size 1.27 1.27)
					(thickness 0.15)
				)
				(justify left bottom)
				(hide yes)
			)
		)
		(property "Description" "SMD Chip Resistor, 3.3 kohm, ± 1%, 63 mW, 0402 [1005 Metric], Thick Film, General Purpose"
			(at 144.78 165.1 0)
			(effects
				(font
					(size 1.27 1.27)
				)
				(hide yes)
			)
		)
		(property "MPN" "CR0402-FX-3301GLF"
			(at 165.1 144.78 0)
			(effects
				(font
					(size 1.27 1.27)
					(thickness 0.15)
				)
				(justify left bottom)
				(hide yes)
			)
		)
		(property "Manufacturer" "Bourns"
			(at 167.64 144.78 0)
			(effects
				(font
					(size 1.27 1.27)
					(thickness 0.15)
				)
				(justify left bottom)
				(hide yes)
			)
		)
		(property "License" "Apache-2.0"
			(at 170.18 144.78 0)
			(effects
				(font
					(size 1.27 1.27)
					(thickness 0.15)
				)
				(justify left bottom)
				(hide yes)
			)
		)
		(property "Author" "Antmicro"
			(at 172.72 144.78 0)
			(effects
				(font
					(size 1.27 1.27)
					(thickness 0.15)
				)
				(justify left bottom)
				(hide yes)
			)
		)
		(property "Val" "3k3"
			(at 146.304 163.83 90)
			(effects
				(font
					(size 1.27 1.27)
					(thickness 0.15)
				)
				(justify right)
			)
		)
		(property "Tolerance" "1%"
			(at 154.94 144.78 0)
			(effects
				(font
					(size 1.27 1.27)
				)
				(justify left bottom)
				(hide yes)
			)
		)
		(pin "2"
		)
		(pin "1"
		)
		(instances
			(project ""
				(path ""
					(reference "R62")
					(unit 1)
				)
			)
		)
	)
	(symbol
		(lib_id "antmicroResistors0402:R_4k53_0402")
		(at 255.27 119.38 90)
		(unit 1)
		(exclude_from_sim no)
		(in_bom yes)
		(on_board yes)
		(dnp no)
		(property "Reference" "R57"
			(at 256.794 114.3 90)
			(effects
				(font
					(size 1.27 1.27)
					(thickness 0.15)
				)
				(justify right)
			)
		)
		(property "Value" "R_4k53_0402"
			(at 267.97 99.06 0)
			(effects
				(font
					(size 1.27 1.27)
					(thickness 0.15)
				)
				(justify left bottom)
				(hide yes)
			)
		)
		(property "Footprint" "antmicro-footprints:R_0402_1005Metric"
			(at 270.51 99.06 0)
			(effects
				(font
					(size 1.27 1.27)
					(thickness 0.15)
				)
				(justify left bottom)
				(hide yes)
			)
		)
		(property "Datasheet" "https://industrial.panasonic.com/cdbs/www-data/pdf/RDM0000/AOA0000C307.pdf"
			(at 273.05 99.06 0)
			(effects
				(font
					(size 1.27 1.27)
					(thickness 0.15)
				)
				(justify left bottom)
				(hide yes)
			)
		)
		(property "Description" "SMD Chip Resistor, 4.53 kohm, ± 0.1%, 62.5 mW, 0402 [1005 Metric], Automotive AEC-Q200 Thin Film"
			(at 255.27 119.38 0)
			(effects
				(font
					(size 1.27 1.27)
				)
				(hide yes)
			)
		)
		(property "MPN" "ERA-2AEB4531X"
			(at 275.59 99.06 0)
			(effects
				(font
					(size 1.27 1.27)
					(thickness 0.15)
				)
				(justify left bottom)
				(hide yes)
			)
		)
		(property "Manufacturer" "Panasonic"
			(at 278.13 99.06 0)
			(effects
				(font
					(size 1.27 1.27)
					(thickness 0.15)
				)
				(justify left bottom)
				(hide yes)
			)
		)
		(property "License" "Apache-2.0"
			(at 280.67 99.06 0)
			(effects
				(font
					(size 1.27 1.27)
					(thickness 0.15)
				)
				(justify left bottom)
				(hide yes)
			)
		)
		(property "Author" "Antmicro"
			(at 283.21 99.06 0)
			(effects
				(font
					(size 1.27 1.27)
					(thickness 0.15)
				)
				(justify left bottom)
				(hide yes)
			)
		)
		(property "Val" "4k53"
			(at 256.794 116.84 90)
			(effects
				(font
					(size 1.27 1.27)
					(thickness 0.15)
				)
				(justify right)
			)
		)
		(property "Tolerance" "0.1%"
			(at 256.794 119.3799 90)
			(effects
				(font
					(size 1.27 1.27)
				)
				(justify right)
			)
		)
		(pin "1"
		)
		(pin "2"
		)
		(instances
			(project "OCuLink to 10GbE adapter"
				(path ""
					(reference "R57")
					(unit 1)
				)
			)
		)
	)
	(symbol
		(lib_id "antmicroInterfaceControllers:EZX710AT2_S_LMR5")
		(at 193.04 167.64 0)
		(unit 3)
		(exclude_from_sim no)
		(in_bom yes)
		(on_board yes)
		(dnp no)
		(fields_autoplaced yes)
		(property "Reference" "U9"
			(at 218.44 160.02 0)
			(effects
				(font
					(size 1.27 1.27)
					(thickness 0.15)
				)
			)
		)
		(property "Value" "EZX710AT2_S_LMR5"
			(at 269.24 172.72 0)
			(effects
				(font
					(size 1.27 1.27)
					(thickness 0.15)
				)
				(justify left bottom)
				(hide yes)
			)
		)
		(property "Footprint" "antmicro-footprints:FCBGA-503_22x22mm_Layout21x24_P1mm"
			(at 269.24 175.26 0)
			(effects
				(font
					(size 1.27 1.27)
					(thickness 0.15)
				)
				(justify left bottom)
				(hide yes)
			)
		)
		(property "Datasheet" "https://www.google.com/url?sa=t&source=web&rct=j&opi=89978449&url=https://cdrdv2-public.intel.com/596333/596333_X710-TM4_Datasheet_v_2_4.pdf&ved=2ahUKEwiSuv20_sCOAxXVCRAIHdxGO_UQFnoECBEQAQ&usg=AOvVaw1CjGyrGWE8ZvOdw4VBsY6U"
			(at 269.24 177.8 0)
			(effects
				(font
					(size 1.27 1.27)
					(thickness 0.15)
				)
				(justify left bottom)
				(hide yes)
			)
		)
		(property "Description" "Ethernet ICs Intel Ethernet Controller 10 Gigabit X7"
			(at 269.24 180.34 0)
			(effects
				(font
					(size 1.27 1.27)
					(thickness 0.15)
				)
				(justify left bottom)
				(hide yes)
			)
		)
		(property "MPN" "EZX710AT2 S LMR5"
			(at 218.44 162.56 0)
			(effects
				(font
					(size 1.27 1.27)
					(thickness 0.15)
				)
			)
		)
		(property "Manufacturer" "Intel"
			(at 269.24 182.88 0)
			(effects
				(font
					(size 1.27 1.27)
					(thickness 0.15)
				)
				(justify left bottom)
				(hide yes)
			)
		)
		(property "Author" "Antmicro"
			(at 269.24 185.42 0)
			(effects
				(font
					(size 1.27 1.27)
					(thickness 0.15)
				)
				(justify left bottom)
				(hide yes)
			)
		)
		(property "License" "Apache-2.0"
			(at 269.24 187.96 0)
			(effects
				(font
					(size 1.27 1.27)
					(thickness 0.15)
				)
				(justify left bottom)
				(hide yes)
			)
		)
		(pin "E39"
		)
		(pin "AD18"
		)
		(pin "AD2"
		)
		(pin "K32"
		)
		(pin "M32"
		)
		(pin "M30"
		)
		(pin "D8"
		)
		(pin "G23"
		)
		(pin "D4"
		)
		(pin "P16"
		)
		(pin "P18"
		)
		(pin "P20"
		)
		(pin "K40"
		)
		(pin "T20"
		)
		(pin "AC31"
		)
		(pin "E5"
		)
		(pin "AD10"
		)
		(pin "W1"
		)
		(pin "G41"
		)
		(pin "W3"
		)
		(pin "U1"
		)
		(pin "H42"
		)
		(pin "H38"
		)
		(pin "K10"
		)
		(pin "U31"
		)
		(pin "V32"
		)
		(pin "C21"
		)
		(pin "B42"
		)
		(pin "V24"
		)
		(pin "P24"
		)
		(pin "Y16"
		)
		(pin "D14"
		)
		(pin "L25"
		)
		(pin "E13"
		)
		(pin "P26"
		)
		(pin "B6"
		)
		(pin "R41"
		)
		(pin "AB32"
		)
		(pin "AB34"
		)
		(pin "R5"
		)
		(pin "T26"
		)
		(pin "AA19"
		)
		(pin "AA21"
		)
		(pin "L37"
		)
		(pin "H2"
		)
		(pin "F22"
		)
		(pin "E19"
		)
		(pin "A17"
		)
		(pin "G19"
		)
		(pin "G21"
		)
		(pin "H34"
		)
		(pin "H36"
		)
		(pin "A15"
		)
		(pin "A19"
		)
		(pin "R39"
		)
		(pin "W37"
		)
		(pin "W39"
		)
		(pin "Y14"
		)
		(pin "L5"
		)
		(pin "N3"
		)
		(pin "N1"
		)
		(pin "T4"
		)
		(pin "B18"
		)
		(pin "W31"
		)
		(pin "W33"
		)
		(pin "W35"
		)
		(pin "W41"
		)
		(pin "C19"
		)
		(pin "C5"
		)
		(pin "M42"
		)
		(pin "G37"
		)
		(pin "L39"
		)
		(pin "F4"
		)
		(pin "AD20"
		)
		(pin "G7"
		)
		(pin "T40"
		)
		(pin "J9"
		)
		(pin "AB18"
		)
		(pin "AA35"
		)
		(pin "H6"
		)
		(pin "M8"
		)
		(pin "A39"
		)
		(pin "P28"
		)
		(pin "Y30"
		)
		(pin "G5"
		)
		(pin "AD32"
		)
		(pin "AD8"
		)
		(pin "AB28"
		)
		(pin "H18"
		)
		(pin "H20"
		)
		(pin "J15"
		)
		(pin "H16"
		)
		(pin "P22"
		)
		(pin "M6"
		)
		(pin "E9"
		)
		(pin "H24"
		)
		(pin "K34"
		)
		(pin "K36"
		)
		(pin "K26"
		)
		(pin "B36"
		)
		(pin "C3"
		)
		(pin "AD22"
		)
		(pin "AA27"
		)
		(pin "V4"
		)
		(pin "B38"
		)
		(pin "D42"
		)
		(pin "F12"
		)
		(pin "AB16"
		)
		(pin "K8"
		)
		(pin "M10"
		)
		(pin "H14"
		)
		(pin "G13"
		)
		(pin "H30"
		)
		(pin "H32"
		)
		(pin "B24"
		)
		(pin "L23"
		)
		(pin "A33"
		)
		(pin "AC25"
		)
		(pin "AC27"
		)
		(pin "P32"
		)
		(pin "P30"
		)
		(pin "H4"
		)
		(pin "U25"
		)
		(pin "V12"
		)
		(pin "V14"
		)
		(pin "V16"
		)
		(pin "W9"
		)
		(pin "T8"
		)
		(pin "AA39"
		)
		(pin "M4"
		)
		(pin "AD24"
		)
		(pin "AD30"
		)
		(pin "U5"
		)
		(pin "U7"
		)
		(pin "AA41"
		)
		(pin "AA9"
		)
		(pin "E17"
		)
		(pin "V36"
		)
		(pin "T42"
		)
		(pin "U27"
		)
		(pin "F16"
		)
		(pin "A23"
		)
		(pin "Y18"
		)
		(pin "V2"
		)
		(pin "V8"
		)
		(pin "L35"
		)
		(pin "H40"
		)
		(pin "N5"
		)
		(pin "AA31"
		)
		(pin "C11"
		)
		(pin "C13"
		)
		(pin "B12"
		)
		(pin "B16"
		)
		(pin "P8"
		)
		(pin "A35"
		)
		(pin "T24"
		)
		(pin "Y38"
		)
		(pin "AC39"
		)
		(pin "J3"
		)
		(pin "U9"
		)
		(pin "K24"
		)
		(pin "AD40"
		)
		(pin "C1"
		)
		(pin "L13"
		)
		(pin "L15"
		)
		(pin "F8"
		)
		(pin "F6"
		)
		(pin "AA7"
		)
		(pin "W25"
		)
		(pin "V42"
		)
		(pin "N7"
		)
		(pin "R9"
		)
		(pin "Y2"
		)
		(pin "F24"
		)
		(pin "F26"
		)
		(pin "C35"
		)
		(pin "C37"
		)
		(pin "J25"
		)
		(pin "AC21"
		)
		(pin "AC23"
		)
		(pin "P42"
		)
		(pin "E11"
		)
		(pin "Y12"
		)
		(pin "A5"
		)
		(pin "V38"
		)
		(pin "AB12"
		)
		(pin "AB4"
		)
		(pin "AB40"
		)
		(pin "AD42"
		)
		(pin "AD6"
		)
		(pin "D10"
		)
		(pin "D2"
		)
		(pin "R23"
		)
		(pin "Y24"
		)
		(pin "T38"
		)
		(pin "AD14"
		)
		(pin "AC41"
		)
		(pin "AC7"
		)
		(pin "Y10"
		)
		(pin "U13"
		)
		(pin "U15"
		)
		(pin "W17"
		)
		(pin "W19"
		)
		(pin "W27"
		)
		(pin "M2"
		)
		(pin "L17"
		)
		(pin "N11"
		)
		(pin "H12"
		)
		(pin "B14"
		)
		(pin "G27"
		)
		(pin "G29"
		)
		(pin "K6"
		)
		(pin "AB42"
		)
		(pin "M24"
		)
		(pin "E7"
		)
		(pin "AC17"
		)
		(pin "AC19"
		)
		(pin "R31"
		)
		(pin "R29"
		)
		(pin "A31"
		)
		(pin "B22"
		)
		(pin "B32"
		)
		(pin "Y36"
		)
		(pin "Y4"
		)
		(pin "Y40"
		)
		(pin "R35"
		)
		(pin "T10"
		)
		(pin "T12"
		)
		(pin "J1"
		)
		(pin "V6"
		)
		(pin "A13"
		)
		(pin "W21"
		)
		(pin "L19"
		)
		(pin "Y6"
		)
		(pin "Y8"
		)
		(pin "A21"
		)
		(pin "G35"
		)
		(pin "G25"
		)
		(pin "C25"
		)
		(pin "C27"
		)
		(pin "J17"
		)
		(pin "K30"
		)
		(pin "W23"
		)
		(pin "M12"
		)
		(pin "M14"
		)
		(pin "M16"
		)
		(pin "D18"
		)
		(pin "K42"
		)
		(pin "T14"
		)
		(pin "T16"
		)
		(pin "T18"
		)
		(pin "T28"
		)
		(pin "U39"
		)
		(pin "N39"
		)
		(pin "U17"
		)
		(pin "U19"
		)
		(pin "R11"
		)
		(pin "T34"
		)
		(pin "P38"
		)
		(pin "E1"
		)
		(pin "C7"
		)
		(pin "C9"
		)
		(pin "F2"
		)
		(pin "J29"
		)
		(pin "J31"
		)
		(pin "U37"
		)
		(pin "AC9"
		)
		(pin "AD12"
		)
		(pin "P40"
		)
		(pin "K4"
		)
		(pin "N9"
		)
		(pin "M40"
		)
		(pin "E3"
		)
		(pin "F18"
		)
		(pin "F20"
		)
		(pin "T6"
		)
		(pin "U3"
		)
		(pin "C29"
		)
		(pin "J27"
		)
		(pin "AB26"
		)
		(pin "AB30"
		)
		(pin "AB2"
		)
		(pin "AA1"
		)
		(pin "P2"
		)
		(pin "R1"
		)
		(pin "R33"
		)
		(pin "AC1"
		)
		(pin "AC11"
		)
		(pin "AA5"
		)
		(pin "AC5"
		)
		(pin "AD4"
		)
		(pin "U41"
		)
		(pin "N19"
		)
		(pin "N21"
		)
		(pin "R37"
		)
		(pin "W5"
		)
		(pin "E25"
		)
		(pin "D22"
		)
		(pin "U29"
		)
		(pin "E29"
		)
		(pin "C33"
		)
		(pin "N33"
		)
		(pin "F14"
		)
		(pin "A29"
		)
		(pin "N35"
		)
		(pin "B34"
		)
		(pin "Y20"
		)
		(pin "AC29"
		)
		(pin "AC3"
		)
		(pin "U21"
		)
		(pin "W11"
		)
		(pin "U23"
		)
		(pin "N41"
		)
		(pin "P4"
		)
		(pin "AC35"
		)
		(pin "AD34"
		)
		(pin "AD38"
		)
		(pin "G39"
		)
		(pin "L11"
		)
		(pin "G11"
		)
		(pin "V26"
		)
		(pin "G31"
		)
		(pin "G33"
		)
		(pin "G9"
		)
		(pin "AA23"
		)
		(pin "AA25"
		)
		(pin "G15"
		)
		(pin "K2"
		)
		(pin "U35"
		)
		(pin "U33"
		)
		(pin "J23"
		)
		(pin "R3"
		)
		(pin "B2"
		)
		(pin "B20"
		)
		(pin "P34"
		)
		(pin "E37"
		)
		(pin "E27"
		)
		(pin "J7"
		)
		(pin "H10"
		)
		(pin "J5"
		)
		(pin "AD16"
		)
		(pin "M26"
		)
		(pin "D12"
		)
		(pin "C15"
		)
		(pin "C17"
		)
		(pin "L41"
		)
		(pin "B40"
		)
		(pin "E41"
		)
		(pin "B4"
		)
		(pin "B8"
		)
		(pin "K28"
		)
		(pin "D20"
		)
		(pin "L33"
		)
		(pin "AB24"
		)
		(pin "AC13"
		)
		(pin "AC15"
		)
		(pin "E21"
		)
		(pin "E23"
		)
		(pin "L3"
		)
		(pin "R7"
		)
		(pin "V40"
		)
		(pin "E33"
		)
		(pin "F40"
		)
		(pin "F42"
		)
		(pin "G3"
		)
		(pin "AA15"
		)
		(pin "AA17"
		)
		(pin "M22"
		)
		(pin "W7"
		)
		(pin "AD26"
		)
		(pin "J35"
		)
		(pin "J33"
		)
		(pin "M28"
		)
		(pin "F34"
		)
		(pin "F36"
		)
		(pin "K18"
		)
		(pin "N27"
		)
		(pin "V34"
		)
		(pin "L7"
		)
		(pin "M36"
		)
		(pin "D26"
		)
		(pin "D28"
		)
		(pin "D36"
		)
		(pin "D38"
		)
		(pin "D40"
		)
		(pin "E31"
		)
		(pin "L9"
		)
		(pin "T2"
		)
		(pin "A9"
		)
		(pin "Y26"
		)
		(pin "Y28"
		)
		(pin "Y32"
		)
		(pin "D6"
		)
		(pin "F38"
		)
		(pin "B10"
		)
		(pin "AA11"
		)
		(pin "AA13"
		)
		(pin "R21"
		)
		(pin "U11"
		)
		(pin "AA29"
		)
		(pin "AA3"
		)
		(pin "H26"
		)
		(pin "H28"
		)
		(pin "K12"
		)
		(pin "K14"
		)
		(pin "AB14"
		)
		(pin "AB20"
		)
		(pin "N23"
		)
		(pin "V10"
		)
		(pin "A11"
		)
		(pin "G1"
		)
		(pin "AB36"
		)
		(pin "AB38"
		)
		(pin "P36"
		)
		(pin "M38"
		)
		(pin "D34"
		)
		(pin "B28"
		)
		(pin "C39"
		)
		(pin "C23"
		)
		(pin "J11"
		)
		(pin "AB22"
		)
		(pin "T22"
		)
		(pin "V30"
		)
		(pin "L31"
		)
		(pin "J13"
		)
		(pin "N25"
		)
		(pin "N31"
		)
		(pin "N29"
		)
		(pin "H22"
		)
		(pin "G17"
		)
		(pin "N37"
		)
		(pin "AD36"
		)
		(pin "A27"
		)
		(pin "F10"
		)
		(pin "AD28"
		)
		(pin "L1"
		)
		(pin "E15"
		)
		(pin "A25"
		)
		(pin "L21"
		)
		(pin "N17"
		)
		(pin "A41"
		)
		(pin "L29"
		)
		(pin "A3"
		)
		(pin "A7"
		)
		(pin "T32"
		)
		(pin "T30"
		)
		(pin "P10"
		)
		(pin "P12"
		)
		(pin "P14"
		)
		(pin "J37"
		)
		(pin "M34"
		)
		(pin "R17"
		)
		(pin "R19"
		)
		(pin "N13"
		)
		(pin "N15"
		)
		(pin "R27"
		)
		(pin "J41"
		)
		(pin "D16"
		)
		(pin "D30"
		)
		(pin "E35"
		)
		(pin "B26"
		)
		(pin "F28"
		)
		(pin "F30"
		)
		(pin "F32"
		)
		(pin "J19"
		)
		(pin "J21"
		)
		(pin "K20"
		)
		(pin "M18"
		)
		(pin "M20"
		)
		(pin "W13"
		)
		(pin "W15"
		)
		(pin "AB10"
		)
		(pin "P6"
		)
		(pin "R25"
		)
		(pin "V22"
		)
		(pin "V18"
		)
		(pin "V20"
		)
		(pin "W29"
		)
		(pin "K22"
		)
		(pin "Y22"
		)
		(pin "AC33"
		)
		(pin "AC37"
		)
		(pin "Y42"
		)
		(pin "R13"
		)
		(pin "R15"
		)
		(pin "H8"
		)
		(pin "Y34"
		)
		(pin "T36"
		)
		(pin "V28"
		)
		(pin "AB6"
		)
		(pin "AB8"
		)
		(pin "D32"
		)
		(pin "J39"
		)
		(pin "L27"
		)
		(pin "C31"
		)
		(pin "C41"
		)
		(pin "D24"
		)
		(pin "K16"
		)
		(pin "K38"
		)
		(pin "B30"
		)
		(pin "AA33"
		)
		(pin "AA37"
		)
		(pin "A37"
		)
		(instances
			(project ""
				(path ""
					(reference "U9")
					(unit 3)
				)
			)
		)
	)
	(symbol
		(lib_id "antmicroCapacitors0402:C_100n_0402")
		(at 158.75 226.06 180)
		(unit 1)
		(exclude_from_sim no)
		(in_bom yes)
		(on_board yes)
		(dnp no)
		(property "Reference" "C69"
			(at 154.686 224.79 0)
			(effects
				(font
					(size 1.27 1.27)
					(thickness 0.15)
				)
				(justify left)
			)
		)
		(property "Value" "C_100n_0402"
			(at 143.51 203.2 0)
			(effects
				(font
					(size 1.27 1.27)
					(thickness 0.15)
				)
				(justify left bottom)
				(hide yes)
			)
		)
		(property "Footprint" "antmicro-footprints:C_0402_1005Metric"
			(at 143.51 200.66 0)
			(effects
				(font
					(size 1.27 1.27)
					(thickness 0.15)
				)
				(justify left bottom)
				(hide yes)
			)
		)
		(property "Datasheet" "https://www.murata.com/products/productdetail?partno=GRM155R61H104KE14%23"
			(at 143.51 198.12 0)
			(effects
				(font
					(size 1.27 1.27)
					(thickness 0.15)
				)
				(justify left bottom)
				(hide yes)
			)
		)
		(property "Description" "SMD Multilayer Ceramic Capacitor, 0.1 µF, 50 V, 0402 [1005 Metric], ± 10%, X5R, GRM Series"
			(at 158.75 226.06 0)
			(effects
				(font
					(size 1.27 1.27)
				)
				(hide yes)
			)
		)
		(property "MPN" "GRM155R61H104KE14D"
			(at 143.51 195.58 0)
			(effects
				(font
					(size 1.27 1.27)
					(thickness 0.15)
				)
				(justify left bottom)
				(hide yes)
			)
		)
		(property "Val" "100n"
			(at 157.734 224.79 0)
			(effects
				(font
					(size 1.27 1.27)
					(thickness 0.15)
				)
				(justify right)
			)
		)
		(property "Voltage" "50V"
			(at 143.51 215.9 0)
			(effects
				(font
					(size 1.27 1.27)
					(thickness 0.15)
				)
				(justify left bottom)
				(hide yes)
			)
		)
		(property "Dielectric" "X5R"
			(at 143.51 213.36 0)
			(effects
				(font
					(size 1.27 1.27)
					(thickness 0.15)
				)
				(justify left bottom)
				(hide yes)
			)
		)
		(property "Manufacturer" "Murata"
			(at 143.51 210.82 0)
			(effects
				(font
					(size 1.27 1.27)
					(thickness 0.15)
				)
				(justify left bottom)
				(hide yes)
			)
		)
		(property "License" "Apache-2.0"
			(at 143.51 208.28 0)
			(effects
				(font
					(size 1.27 1.27)
					(thickness 0.15)
				)
				(justify left bottom)
				(hide yes)
			)
		)
		(property "Author" "Antmicro"
			(at 143.51 205.74 0)
			(effects
				(font
					(size 1.27 1.27)
					(thickness 0.15)
				)
				(justify left bottom)
				(hide yes)
			)
		)
		(pin "2"
		)
		(pin "1"
		)
		(instances
			(project "OCuLink to 10GbE adapter"
				(path ""
					(reference "C69")
					(unit 1)
				)
			)
		)
	)
	(symbol
		(lib_id "antmicroCapacitors0402:C_10p_0402")
		(at 91.44 180.34 90)
		(unit 1)
		(exclude_from_sim no)
		(in_bom yes)
		(on_board yes)
		(dnp no)
		(property "Reference" "C216"
			(at 93.218 176.53 90)
			(effects
				(font
					(size 1.27 1.27)
					(thickness 0.15)
				)
				(justify right)
			)
		)
		(property "Value" "C_10p_0402"
			(at 101.6 160.02 0)
			(effects
				(font
					(size 1.27 1.27)
					(thickness 0.15)
				)
				(justify left bottom)
				(hide yes)
			)
		)
		(property "Footprint" "antmicro-footprints:C_0402_1005Metric"
			(at 104.14 160.02 0)
			(effects
				(font
					(size 1.27 1.27)
					(thickness 0.15)
				)
				(justify left bottom)
				(hide yes)
			)
		)
		(property "Datasheet" "https://www.murata.com/products/productdetail?partno=GCM1555C1H100GA16%23"
			(at 106.68 160.02 0)
			(effects
				(font
					(size 1.27 1.27)
					(thickness 0.15)
				)
				(justify left bottom)
				(hide yes)
			)
		)
		(property "Description" "SMD Multilayer Ceramic Capacitor, 10 pF, 50 V, 0402 [1005 Metric], ± 2%, C0G / NP0, GCM"
			(at 124.46 160.02 0)
			(effects
				(font
					(size 1.27 1.27)
				)
				(justify left bottom)
				(hide yes)
			)
		)
		(property "MPN" "GCM1555C1H100GA16D"
			(at 109.22 160.02 0)
			(effects
				(font
					(size 1.27 1.27)
					(thickness 0.15)
				)
				(justify left bottom)
				(hide yes)
			)
		)
		(property "Manufacturer" "Murata"
			(at 111.76 160.02 0)
			(effects
				(font
					(size 1.27 1.27)
					(thickness 0.15)
				)
				(justify left bottom)
				(hide yes)
			)
		)
		(property "License" "Apache-2.0"
			(at 114.3 160.02 0)
			(effects
				(font
					(size 1.27 1.27)
					(thickness 0.15)
				)
				(justify left bottom)
				(hide yes)
			)
		)
		(property "Author" "Antmicro"
			(at 116.84 160.02 0)
			(effects
				(font
					(size 1.27 1.27)
					(thickness 0.15)
				)
				(justify left bottom)
				(hide yes)
			)
		)
		(property "Val" "10p"
			(at 93.218 179.07 90)
			(effects
				(font
					(size 1.27 1.27)
					(thickness 0.15)
				)
				(justify right)
			)
		)
		(property "Voltage" "50V"
			(at 119.38 160.02 0)
			(effects
				(font
					(size 1.27 1.27)
				)
				(justify left bottom)
				(hide yes)
			)
		)
		(property "Dielectric" "C0G"
			(at 121.92 160.02 0)
			(effects
				(font
					(size 1.27 1.27)
				)
				(justify left bottom)
				(hide yes)
			)
		)
		(pin "2"
		)
		(pin "1"
		)
		(instances
			(project "oculink-to-10gbe-adapter"
				(path ""
					(reference "C216")
					(unit 1)
				)
			)
		)
	)
	(symbol
		(lib_id "antmicroResistors0402:R_0R_0402")
		(at 251.46 238.76 90)
		(unit 1)
		(exclude_from_sim no)
		(in_bom yes)
		(on_board yes)
		(dnp no)
		(property "Reference" "R74"
			(at 252.984 234.95 90)
			(effects
				(font
					(size 1.27 1.27)
					(thickness 0.15)
				)
				(justify right)
			)
		)
		(property "Value" "R_0R_0402"
			(at 264.16 218.44 0)
			(effects
				(font
					(size 1.27 1.27)
					(thickness 0.15)
				)
				(justify left bottom)
				(hide yes)
			)
		)
		(property "Footprint" "antmicro-footprints:R_0402_1005Metric"
			(at 266.7 218.44 0)
			(effects
				(font
					(size 1.27 1.27)
					(thickness 0.15)
				)
				(justify left bottom)
				(hide yes)
			)
		)
		(property "Datasheet" "https://industrial.panasonic.com/cdbs/www-data/pdf/RDA0000/AOA0000C301.pdf"
			(at 269.24 218.44 0)
			(effects
				(font
					(size 1.27 1.27)
					(thickness 0.15)
				)
				(justify left bottom)
				(hide yes)
			)
		)
		(property "Description" "SMD Chip Resistor, Jumper, 0 ohm, 100 mW, 0402 [1005 Metric], Thick Film, General Purpose"
			(at 251.46 238.76 0)
			(effects
				(font
					(size 1.27 1.27)
				)
				(hide yes)
			)
		)
		(property "MPN" "ERJ2GE0R00X"
			(at 271.78 218.44 0)
			(effects
				(font
					(size 1.27 1.27)
					(thickness 0.15)
				)
				(justify left bottom)
				(hide yes)
			)
		)
		(property "Manufacturer" "Panasonic"
			(at 274.32 218.44 0)
			(effects
				(font
					(size 1.27 1.27)
					(thickness 0.15)
				)
				(justify left bottom)
				(hide yes)
			)
		)
		(property "License" "Apache-2.0"
			(at 276.86 218.44 0)
			(effects
				(font
					(size 1.27 1.27)
					(thickness 0.15)
				)
				(justify left bottom)
				(hide yes)
			)
		)
		(property "Author" "Antmicro"
			(at 279.4 218.44 0)
			(effects
				(font
					(size 1.27 1.27)
					(thickness 0.15)
				)
				(justify left bottom)
				(hide yes)
			)
		)
		(property "Val" "0R"
			(at 252.984 237.49 90)
			(effects
				(font
					(size 1.27 1.27)
					(thickness 0.15)
				)
				(justify right)
			)
		)
		(property "Tolerance" "~"
			(at 261.62 218.44 0)
			(effects
				(font
					(size 1.27 1.27)
				)
				(justify left bottom)
				(hide yes)
			)
		)
		(property "Current" "1A"
			(at 281.94 218.44 0)
			(effects
				(font
					(size 1.27 1.27)
					(thickness 0.15)
				)
				(justify left bottom)
				(hide yes)
			)
		)
		(pin "1"
		)
		(pin "2"
		)
		(instances
			(project "OCuLink to 10GbE adapter"
				(path ""
					(reference "R74")
					(unit 1)
				)
			)
		)
	)
	(symbol
		(lib_id "antmicroResistors0402:R_3k3_0402")
		(at 137.16 165.1 90)
		(unit 1)
		(exclude_from_sim no)
		(in_bom yes)
		(on_board yes)
		(dnp no)
		(property "Reference" "R61"
			(at 138.684 161.29 90)
			(effects
				(font
					(size 1.27 1.27)
					(thickness 0.15)
				)
				(justify right)
			)
		)
		(property "Value" "R_3k3_0402"
			(at 149.86 144.78 0)
			(effects
				(font
					(size 1.27 1.27)
					(thickness 0.15)
				)
				(justify left bottom)
				(hide yes)
			)
		)
		(property "Footprint" "antmicro-footprints:R_0402_1005Metric"
			(at 152.4 144.78 0)
			(effects
				(font
					(size 1.27 1.27)
					(thickness 0.15)
				)
				(justify left bottom)
				(hide yes)
			)
		)
		(property "Datasheet" "https://www.bourns.com/docs/product-datasheets/cr.pdf"
			(at 154.94 144.78 0)
			(effects
				(font
					(size 1.27 1.27)
					(thickness 0.15)
				)
				(justify left bottom)
				(hide yes)
			)
		)
		(property "Description" "SMD Chip Resistor, 3.3 kohm, ± 1%, 63 mW, 0402 [1005 Metric], Thick Film, General Purpose"
			(at 137.16 165.1 0)
			(effects
				(font
					(size 1.27 1.27)
				)
				(hide yes)
			)
		)
		(property "MPN" "CR0402-FX-3301GLF"
			(at 157.48 144.78 0)
			(effects
				(font
					(size 1.27 1.27)
					(thickness 0.15)
				)
				(justify left bottom)
				(hide yes)
			)
		)
		(property "Manufacturer" "Bourns"
			(at 160.02 144.78 0)
			(effects
				(font
					(size 1.27 1.27)
					(thickness 0.15)
				)
				(justify left bottom)
				(hide yes)
			)
		)
		(property "License" "Apache-2.0"
			(at 162.56 144.78 0)
			(effects
				(font
					(size 1.27 1.27)
					(thickness 0.15)
				)
				(justify left bottom)
				(hide yes)
			)
		)
		(property "Author" "Antmicro"
			(at 165.1 144.78 0)
			(effects
				(font
					(size 1.27 1.27)
					(thickness 0.15)
				)
				(justify left bottom)
				(hide yes)
			)
		)
		(property "Val" "3k3"
			(at 138.684 163.83 90)
			(effects
				(font
					(size 1.27 1.27)
					(thickness 0.15)
				)
				(justify right)
			)
		)
		(property "Tolerance" "1%"
			(at 147.32 144.78 0)
			(effects
				(font
					(size 1.27 1.27)
				)
				(justify left bottom)
				(hide yes)
			)
		)
		(pin "2"
		)
		(pin "1"
		)
		(instances
			(project "OCuLink to 10GbE adapter"
				(path ""
					(reference "R61")
					(unit 1)
				)
			)
		)
	)
	(symbol
		(lib_id "antmicroResistors0402:R_1k_0402")
		(at 251.46 226.06 90)
		(unit 1)
		(exclude_from_sim no)
		(in_bom no)
		(on_board yes)
		(dnp yes)
		(property "Reference" "R72"
			(at 252.984 222.25 90)
			(effects
				(font
					(size 1.27 1.27)
					(thickness 0.15)
				)
				(justify right)
			)
		)
		(property "Value" "R_1k_0402"
			(at 264.16 205.74 0)
			(effects
				(font
					(size 1.27 1.27)
					(thickness 0.15)
				)
				(justify left bottom)
				(hide yes)
			)
		)
		(property "Footprint" "antmicro-footprints:R_0402_1005Metric"
			(at 266.7 205.74 0)
			(effects
				(font
					(size 1.27 1.27)
					(thickness 0.15)
				)
				(justify left bottom)
				(hide yes)
			)
		)
		(property "Datasheet" "https://www.bourns.com/docs/product-datasheets/cr.pdf"
			(at 269.24 205.74 0)
			(effects
				(font
					(size 1.27 1.27)
					(thickness 0.15)
				)
				(justify left bottom)
				(hide yes)
			)
		)
		(property "Description" "SMD Chip Resistor, 1 kohm, ± 1%, 63 mW, 0402 [1005 Metric], Thick Film, General Purpose"
			(at 251.46 226.06 0)
			(effects
				(font
					(size 1.27 1.27)
				)
				(hide yes)
			)
		)
		(property "MPN" "CR0402-FX-1001GLF"
			(at 271.78 205.74 0)
			(effects
				(font
					(size 1.27 1.27)
					(thickness 0.15)
				)
				(justify left bottom)
				(hide yes)
			)
		)
		(property "Manufacturer" "Bourns"
			(at 274.32 205.74 0)
			(effects
				(font
					(size 1.27 1.27)
					(thickness 0.15)
				)
				(justify left bottom)
				(hide yes)
			)
		)
		(property "License" "Apache-2.0"
			(at 276.86 205.74 0)
			(effects
				(font
					(size 1.27 1.27)
					(thickness 0.15)
				)
				(justify left bottom)
				(hide yes)
			)
		)
		(property "Author" "Antmicro"
			(at 279.4 205.74 0)
			(effects
				(font
					(size 1.27 1.27)
					(thickness 0.15)
				)
				(justify left bottom)
				(hide yes)
			)
		)
		(property "Val" "1k"
			(at 252.984 224.79 90)
			(effects
				(font
					(size 1.27 1.27)
					(thickness 0.15)
				)
				(justify right)
			)
		)
		(property "Tolerance" "1%"
			(at 261.62 205.74 0)
			(effects
				(font
					(size 1.27 1.27)
				)
				(justify left bottom)
				(hide yes)
			)
		)
		(pin "2"
		)
		(pin "1"
		)
		(instances
			(project "OCuLink to 10GbE adapter"
				(path ""
					(reference "R72")
					(unit 1)
				)
			)
		)
	)
	(symbol
		(lib_id "antmicropower:GND")
		(at 53.34 236.22 0)
		(unit 1)
		(exclude_from_sim no)
		(in_bom yes)
		(on_board yes)
		(dnp no)
		(property "Reference" "#PWR091"
			(at 62.23 238.76 0)
			(effects
				(font
					(size 1.27 1.27)
					(thickness 0.15)
				)
				(justify left bottom)
				(hide yes)
			)
		)
		(property "Value" "GND"
			(at 53.34 240.03 0)
			(effects
				(font
					(size 1.27 1.27)
					(thickness 0.15)
				)
			)
		)
		(property "Footprint" ""
			(at 62.23 243.84 0)
			(effects
				(font
					(size 1.27 1.27)
					(thickness 0.15)
				)
				(justify left bottom)
				(hide yes)
			)
		)
		(property "Datasheet" ""
			(at 62.23 248.92 0)
			(effects
				(font
					(size 1.27 1.27)
					(thickness 0.15)
				)
				(justify left bottom)
				(hide yes)
			)
		)
		(property "Description" ""
			(at 53.34 236.22 0)
			(effects
				(font
					(size 1.27 1.27)
				)
				(hide yes)
			)
		)
		(property "Author" "Antmicro"
			(at 62.23 243.84 0)
			(effects
				(font
					(size 1.27 1.27)
					(thickness 0.15)
				)
				(justify left bottom)
				(hide yes)
			)
		)
		(property "License" "Apache-2.0"
			(at 62.23 246.38 0)
			(effects
				(font
					(size 1.27 1.27)
					(thickness 0.15)
				)
				(justify left bottom)
				(hide yes)
			)
		)
		(pin "1"
		)
		(instances
			(project "OCuLink to 10GbE adapter"
				(path ""
					(reference "#PWR091")
					(unit 1)
				)
			)
		)
	)
	(symbol
		(lib_id "antmicropower:GND")
		(at 142.24 236.22 0)
		(unit 1)
		(exclude_from_sim no)
		(in_bom yes)
		(on_board yes)
		(dnp no)
		(property "Reference" "#PWR094"
			(at 151.13 238.76 0)
			(effects
				(font
					(size 1.27 1.27)
					(thickness 0.15)
				)
				(justify left bottom)
				(hide yes)
			)
		)
		(property "Value" "GND"
			(at 142.24 240.03 0)
			(effects
				(font
					(size 1.27 1.27)
					(thickness 0.15)
				)
			)
		)
		(property "Footprint" ""
			(at 151.13 243.84 0)
			(effects
				(font
					(size 1.27 1.27)
					(thickness 0.15)
				)
				(justify left bottom)
				(hide yes)
			)
		)
		(property "Datasheet" ""
			(at 151.13 248.92 0)
			(effects
				(font
					(size 1.27 1.27)
					(thickness 0.15)
				)
				(justify left bottom)
				(hide yes)
			)
		)
		(property "Description" ""
			(at 142.24 236.22 0)
			(effects
				(font
					(size 1.27 1.27)
				)
				(hide yes)
			)
		)
		(property "Author" "Antmicro"
			(at 151.13 243.84 0)
			(effects
				(font
					(size 1.27 1.27)
					(thickness 0.15)
				)
				(justify left bottom)
				(hide yes)
			)
		)
		(property "License" "Apache-2.0"
			(at 151.13 246.38 0)
			(effects
				(font
					(size 1.27 1.27)
					(thickness 0.15)
				)
				(justify left bottom)
				(hide yes)
			)
		)
		(pin "1"
		)
		(instances
			(project "OCuLink to 10GbE adapter"
				(path ""
					(reference "#PWR094")
					(unit 1)
				)
			)
		)
	)
	(symbol
		(lib_id "antmicropower:GND")
		(at 251.46 241.3 0)
		(unit 1)
		(exclude_from_sim no)
		(in_bom yes)
		(on_board yes)
		(dnp no)
		(property "Reference" "#PWR0255"
			(at 260.35 243.84 0)
			(effects
				(font
					(size 1.27 1.27)
					(thickness 0.15)
				)
				(justify left bottom)
				(hide yes)
			)
		)
		(property "Value" "GND"
			(at 251.46 245.11 0)
			(effects
				(font
					(size 1.27 1.27)
					(thickness 0.15)
				)
			)
		)
		(property "Footprint" ""
			(at 260.35 248.92 0)
			(effects
				(font
					(size 1.27 1.27)
					(thickness 0.15)
				)
				(justify left bottom)
				(hide yes)
			)
		)
		(property "Datasheet" ""
			(at 260.35 254 0)
			(effects
				(font
					(size 1.27 1.27)
					(thickness 0.15)
				)
				(justify left bottom)
				(hide yes)
			)
		)
		(property "Description" ""
			(at 251.46 241.3 0)
			(effects
				(font
					(size 1.27 1.27)
				)
				(hide yes)
			)
		)
		(property "Author" "Antmicro"
			(at 260.35 248.92 0)
			(effects
				(font
					(size 1.27 1.27)
					(thickness 0.15)
				)
				(justify left bottom)
				(hide yes)
			)
		)
		(property "License" "Apache-2.0"
			(at 260.35 251.46 0)
			(effects
				(font
					(size 1.27 1.27)
					(thickness 0.15)
				)
				(justify left bottom)
				(hide yes)
			)
		)
		(pin "1"
		)
		(instances
			(project "OCuLink to 10GbE adapter"
				(path ""
					(reference "#PWR0255")
					(unit 1)
				)
			)
		)
	)
	(symbol
		(lib_id "antmicropower:PWR_FLAG")
		(at 58.42 214.63 0)
		(unit 1)
		(exclude_from_sim no)
		(in_bom yes)
		(on_board yes)
		(dnp no)
		(property "Reference" "#FLG011"
			(at 58.42 212.725 0)
			(effects
				(font
					(size 1.27 1.27)
				)
				(hide yes)
			)
		)
		(property "Value" "PWR_FLAG"
			(at 58.42 210.82 0)
			(effects
				(font
					(size 1.27 1.27)
				)
			)
		)
		(property "Footprint" ""
			(at 58.42 214.63 0)
			(effects
				(font
					(size 1.27 1.27)
				)
				(hide yes)
			)
		)
		(property "Datasheet" ""
			(at 58.42 214.63 0)
			(effects
				(font
					(size 1.27 1.27)
				)
				(hide yes)
			)
		)
		(property "Description" ""
			(at 58.42 214.63 0)
			(effects
				(font
					(size 1.27 1.27)
				)
				(hide yes)
			)
		)
		(pin "1"
		)
		(instances
			(project "OCuLink to 10GbE adapter"
				(path ""
					(reference "#FLG011")
					(unit 1)
				)
			)
		)
	)
	(symbol
		(lib_id "antmicroResistors0402:R_3k3_0402")
		(at 129.54 165.1 90)
		(unit 1)
		(exclude_from_sim no)
		(in_bom yes)
		(on_board yes)
		(dnp no)
		(property "Reference" "R60"
			(at 131.064 161.29 90)
			(effects
				(font
					(size 1.27 1.27)
					(thickness 0.15)
				)
				(justify right)
			)
		)
		(property "Value" "R_3k3_0402"
			(at 142.24 144.78 0)
			(effects
				(font
					(size 1.27 1.27)
					(thickness 0.15)
				)
				(justify left bottom)
				(hide yes)
			)
		)
		(property "Footprint" "antmicro-footprints:R_0402_1005Metric"
			(at 144.78 144.78 0)
			(effects
				(font
					(size 1.27 1.27)
					(thickness 0.15)
				)
				(justify left bottom)
				(hide yes)
			)
		)
		(property "Datasheet" "https://www.bourns.com/docs/product-datasheets/cr.pdf"
			(at 147.32 144.78 0)
			(effects
				(font
					(size 1.27 1.27)
					(thickness 0.15)
				)
				(justify left bottom)
				(hide yes)
			)
		)
		(property "Description" "SMD Chip Resistor, 3.3 kohm, ± 1%, 63 mW, 0402 [1005 Metric], Thick Film, General Purpose"
			(at 129.54 165.1 0)
			(effects
				(font
					(size 1.27 1.27)
				)
				(hide yes)
			)
		)
		(property "MPN" "CR0402-FX-3301GLF"
			(at 149.86 144.78 0)
			(effects
				(font
					(size 1.27 1.27)
					(thickness 0.15)
				)
				(justify left bottom)
				(hide yes)
			)
		)
		(property "Manufacturer" "Bourns"
			(at 152.4 144.78 0)
			(effects
				(font
					(size 1.27 1.27)
					(thickness 0.15)
				)
				(justify left bottom)
				(hide yes)
			)
		)
		(property "License" "Apache-2.0"
			(at 154.94 144.78 0)
			(effects
				(font
					(size 1.27 1.27)
					(thickness 0.15)
				)
				(justify left bottom)
				(hide yes)
			)
		)
		(property "Author" "Antmicro"
			(at 157.48 144.78 0)
			(effects
				(font
					(size 1.27 1.27)
					(thickness 0.15)
				)
				(justify left bottom)
				(hide yes)
			)
		)
		(property "Val" "3k3"
			(at 131.064 163.83 90)
			(effects
				(font
					(size 1.27 1.27)
					(thickness 0.15)
				)
				(justify right)
			)
		)
		(property "Tolerance" "1%"
			(at 139.7 144.78 0)
			(effects
				(font
					(size 1.27 1.27)
				)
				(justify left bottom)
				(hide yes)
			)
		)
		(pin "2"
		)
		(pin "1"
		)
		(instances
			(project "OCuLink to 10GbE adapter"
				(path ""
					(reference "R60")
					(unit 1)
				)
			)
		)
	)
	(symbol
		(lib_id "antmicropower:GND")
		(at 38.1 236.22 0)
		(unit 1)
		(exclude_from_sim no)
		(in_bom yes)
		(on_board yes)
		(dnp no)
		(property "Reference" "#PWR090"
			(at 46.99 238.76 0)
			(effects
				(font
					(size 1.27 1.27)
					(thickness 0.15)
				)
				(justify left bottom)
				(hide yes)
			)
		)
		(property "Value" "GND"
			(at 38.1 240.03 0)
			(effects
				(font
					(size 1.27 1.27)
					(thickness 0.15)
				)
			)
		)
		(property "Footprint" ""
			(at 46.99 243.84 0)
			(effects
				(font
					(size 1.27 1.27)
					(thickness 0.15)
				)
				(justify left bottom)
				(hide yes)
			)
		)
		(property "Datasheet" ""
			(at 46.99 248.92 0)
			(effects
				(font
					(size 1.27 1.27)
					(thickness 0.15)
				)
				(justify left bottom)
				(hide yes)
			)
		)
		(property "Description" ""
			(at 38.1 236.22 0)
			(effects
				(font
					(size 1.27 1.27)
				)
				(hide yes)
			)
		)
		(property "Author" "Antmicro"
			(at 46.99 243.84 0)
			(effects
				(font
					(size 1.27 1.27)
					(thickness 0.15)
				)
				(justify left bottom)
				(hide yes)
			)
		)
		(property "License" "Apache-2.0"
			(at 46.99 246.38 0)
			(effects
				(font
					(size 1.27 1.27)
					(thickness 0.15)
				)
				(justify left bottom)
				(hide yes)
			)
		)
		(pin "1"
		)
		(instances
			(project "OCuLink to 10GbE adapter"
				(path ""
					(reference "#PWR090")
					(unit 1)
				)
			)
		)
	)
	(symbol
		(lib_id "antmicroResistors0402:R_3k3_0402")
		(at 121.92 165.1 90)
		(unit 1)
		(exclude_from_sim no)
		(in_bom yes)
		(on_board yes)
		(dnp no)
		(property "Reference" "R59"
			(at 123.444 161.29 90)
			(effects
				(font
					(size 1.27 1.27)
					(thickness 0.15)
				)
				(justify right)
			)
		)
		(property "Value" "R_3k3_0402"
			(at 134.62 144.78 0)
			(effects
				(font
					(size 1.27 1.27)
					(thickness 0.15)
				)
				(justify left bottom)
				(hide yes)
			)
		)
		(property "Footprint" "antmicro-footprints:R_0402_1005Metric"
			(at 137.16 144.78 0)
			(effects
				(font
					(size 1.27 1.27)
					(thickness 0.15)
				)
				(justify left bottom)
				(hide yes)
			)
		)
		(property "Datasheet" "https://www.bourns.com/docs/product-datasheets/cr.pdf"
			(at 139.7 144.78 0)
			(effects
				(font
					(size 1.27 1.27)
					(thickness 0.15)
				)
				(justify left bottom)
				(hide yes)
			)
		)
		(property "Description" "SMD Chip Resistor, 3.3 kohm, ± 1%, 63 mW, 0402 [1005 Metric], Thick Film, General Purpose"
			(at 121.92 165.1 0)
			(effects
				(font
					(size 1.27 1.27)
				)
				(hide yes)
			)
		)
		(property "MPN" "CR0402-FX-3301GLF"
			(at 142.24 144.78 0)
			(effects
				(font
					(size 1.27 1.27)
					(thickness 0.15)
				)
				(justify left bottom)
				(hide yes)
			)
		)
		(property "Manufacturer" "Bourns"
			(at 144.78 144.78 0)
			(effects
				(font
					(size 1.27 1.27)
					(thickness 0.15)
				)
				(justify left bottom)
				(hide yes)
			)
		)
		(property "License" "Apache-2.0"
			(at 147.32 144.78 0)
			(effects
				(font
					(size 1.27 1.27)
					(thickness 0.15)
				)
				(justify left bottom)
				(hide yes)
			)
		)
		(property "Author" "Antmicro"
			(at 149.86 144.78 0)
			(effects
				(font
					(size 1.27 1.27)
					(thickness 0.15)
				)
				(justify left bottom)
				(hide yes)
			)
		)
		(property "Val" "3k3"
			(at 123.444 163.83 90)
			(effects
				(font
					(size 1.27 1.27)
					(thickness 0.15)
				)
				(justify right)
			)
		)
		(property "Tolerance" "1%"
			(at 132.08 144.78 0)
			(effects
				(font
					(size 1.27 1.27)
				)
				(justify left bottom)
				(hide yes)
			)
		)
		(pin "2"
		)
		(pin "1"
		)
		(instances
			(project "OCuLink to 10GbE adapter"
				(path ""
					(reference "R59")
					(unit 1)
				)
			)
		)
	)
	(symbol
		(lib_id "antmicroResistors0402:R_3k3_0402")
		(at 160.02 165.1 90)
		(unit 1)
		(exclude_from_sim no)
		(in_bom yes)
		(on_board yes)
		(dnp no)
		(property "Reference" "R64"
			(at 161.544 161.29 90)
			(effects
				(font
					(size 1.27 1.27)
					(thickness 0.15)
				)
				(justify right)
			)
		)
		(property "Value" "R_3k3_0402"
			(at 172.72 144.78 0)
			(effects
				(font
					(size 1.27 1.27)
					(thickness 0.15)
				)
				(justify left bottom)
				(hide yes)
			)
		)
		(property "Footprint" "antmicro-footprints:R_0402_1005Metric"
			(at 175.26 144.78 0)
			(effects
				(font
					(size 1.27 1.27)
					(thickness 0.15)
				)
				(justify left bottom)
				(hide yes)
			)
		)
		(property "Datasheet" "https://www.bourns.com/docs/product-datasheets/cr.pdf"
			(at 177.8 144.78 0)
			(effects
				(font
					(size 1.27 1.27)
					(thickness 0.15)
				)
				(justify left bottom)
				(hide yes)
			)
		)
		(property "Description" "SMD Chip Resistor, 3.3 kohm, ± 1%, 63 mW, 0402 [1005 Metric], Thick Film, General Purpose"
			(at 160.02 165.1 0)
			(effects
				(font
					(size 1.27 1.27)
				)
				(hide yes)
			)
		)
		(property "MPN" "CR0402-FX-3301GLF"
			(at 180.34 144.78 0)
			(effects
				(font
					(size 1.27 1.27)
					(thickness 0.15)
				)
				(justify left bottom)
				(hide yes)
			)
		)
		(property "Manufacturer" "Bourns"
			(at 182.88 144.78 0)
			(effects
				(font
					(size 1.27 1.27)
					(thickness 0.15)
				)
				(justify left bottom)
				(hide yes)
			)
		)
		(property "License" "Apache-2.0"
			(at 185.42 144.78 0)
			(effects
				(font
					(size 1.27 1.27)
					(thickness 0.15)
				)
				(justify left bottom)
				(hide yes)
			)
		)
		(property "Author" "Antmicro"
			(at 187.96 144.78 0)
			(effects
				(font
					(size 1.27 1.27)
					(thickness 0.15)
				)
				(justify left bottom)
				(hide yes)
			)
		)
		(property "Val" "3k3"
			(at 161.544 163.83 90)
			(effects
				(font
					(size 1.27 1.27)
					(thickness 0.15)
				)
				(justify right)
			)
		)
		(property "Tolerance" "1%"
			(at 170.18 144.78 0)
			(effects
				(font
					(size 1.27 1.27)
				)
				(justify left bottom)
				(hide yes)
			)
		)
		(pin "2"
		)
		(pin "1"
		)
		(instances
			(project "OCuLink to 10GbE adapter"
				(path ""
					(reference "R64")
					(unit 1)
				)
			)
		)
	)
	(symbol
		(lib_id "antmicropower:+3V3")
		(at 38.1 214.63 0)
		(unit 1)
		(exclude_from_sim no)
		(in_bom yes)
		(on_board yes)
		(dnp no)
		(property "Reference" "#PWR089"
			(at 53.34 214.63 0)
			(effects
				(font
					(size 1.27 1.27)
					(thickness 0.15)
				)
				(justify left bottom)
				(hide yes)
			)
		)
		(property "Value" "+3V3"
			(at 38.1 210.82 0)
			(effects
				(font
					(size 1.27 1.27)
					(thickness 0.15)
				)
			)
		)
		(property "Footprint" ""
			(at 53.34 222.25 0)
			(effects
				(font
					(size 1.27 1.27)
					(thickness 0.15)
				)
				(justify left bottom)
				(hide yes)
			)
		)
		(property "Datasheet" ""
			(at 53.34 224.79 0)
			(effects
				(font
					(size 1.27 1.27)
					(thickness 0.15)
				)
				(justify left bottom)
				(hide yes)
			)
		)
		(property "Description" ""
			(at 38.1 214.63 0)
			(effects
				(font
					(size 1.27 1.27)
				)
				(hide yes)
			)
		)
		(property "Author" "Antmicro"
			(at 53.34 217.17 0)
			(effects
				(font
					(size 1.27 1.27)
					(thickness 0.15)
				)
				(justify left bottom)
				(hide yes)
			)
		)
		(property "License" "Apache-2.0"
			(at 53.34 219.71 0)
			(effects
				(font
					(size 1.27 1.27)
					(thickness 0.15)
				)
				(justify left bottom)
				(hide yes)
			)
		)
		(pin "1"
		)
		(instances
			(project "OCuLink to 10GbE adapter"
				(path ""
					(reference "#PWR089")
					(unit 1)
				)
			)
		)
	)
	(symbol
		(lib_id "antmicroResistors0402:R_0R_0402")
		(at 153.67 198.12 0)
		(unit 1)
		(exclude_from_sim no)
		(in_bom yes)
		(on_board yes)
		(dnp no)
		(property "Reference" "R69"
			(at 153.67 196.85 0)
			(effects
				(font
					(size 1.27 1.27)
					(thickness 0.15)
				)
				(justify right)
			)
		)
		(property "Value" "R_0R_0402"
			(at 173.99 210.82 0)
			(effects
				(font
					(size 1.27 1.27)
					(thickness 0.15)
				)
				(justify left bottom)
				(hide yes)
			)
		)
		(property "Footprint" "antmicro-footprints:R_0402_1005Metric"
			(at 173.99 213.36 0)
			(effects
				(font
					(size 1.27 1.27)
					(thickness 0.15)
				)
				(justify left bottom)
				(hide yes)
			)
		)
		(property "Datasheet" "https://industrial.panasonic.com/cdbs/www-data/pdf/RDA0000/AOA0000C301.pdf"
			(at 173.99 215.9 0)
			(effects
				(font
					(size 1.27 1.27)
					(thickness 0.15)
				)
				(justify left bottom)
				(hide yes)
			)
		)
		(property "Description" "SMD Chip Resistor, Jumper, 0 ohm, 100 mW, 0402 [1005 Metric], Thick Film, General Purpose"
			(at 153.67 198.12 0)
			(effects
				(font
					(size 1.27 1.27)
				)
				(hide yes)
			)
		)
		(property "MPN" "ERJ2GE0R00X"
			(at 173.99 218.44 0)
			(effects
				(font
					(size 1.27 1.27)
					(thickness 0.15)
				)
				(justify left bottom)
				(hide yes)
			)
		)
		(property "Manufacturer" "Panasonic"
			(at 173.99 220.98 0)
			(effects
				(font
					(size 1.27 1.27)
					(thickness 0.15)
				)
				(justify left bottom)
				(hide yes)
			)
		)
		(property "License" "Apache-2.0"
			(at 173.99 223.52 0)
			(effects
				(font
					(size 1.27 1.27)
					(thickness 0.15)
				)
				(justify left bottom)
				(hide yes)
			)
		)
		(property "Author" "Antmicro"
			(at 173.99 226.06 0)
			(effects
				(font
					(size 1.27 1.27)
					(thickness 0.15)
				)
				(justify left bottom)
				(hide yes)
			)
		)
		(property "Val" "0R"
			(at 158.75 196.85 0)
			(effects
				(font
					(size 1.27 1.27)
					(thickness 0.15)
				)
				(justify left)
			)
		)
		(property "Tolerance" "~"
			(at 173.99 208.28 0)
			(effects
				(font
					(size 1.27 1.27)
				)
				(justify left bottom)
				(hide yes)
			)
		)
		(property "Current" "1A"
			(at 173.99 228.6 0)
			(effects
				(font
					(size 1.27 1.27)
					(thickness 0.15)
				)
				(justify left bottom)
				(hide yes)
			)
		)
		(pin "1"
		)
		(pin "2"
		)
		(instances
			(project ""
				(path ""
					(reference "R69")
					(unit 1)
				)
			)
		)
	)
	(symbol
		(lib_id "antmicroResistors0402:R_1k_0402")
		(at 261.62 226.06 90)
		(unit 1)
		(exclude_from_sim no)
		(in_bom no)
		(on_board yes)
		(dnp yes)
		(property "Reference" "R73"
			(at 263.144 222.25 90)
			(effects
				(font
					(size 1.27 1.27)
					(thickness 0.15)
				)
				(justify right)
			)
		)
		(property "Value" "R_1k_0402"
			(at 274.32 205.74 0)
			(effects
				(font
					(size 1.27 1.27)
					(thickness 0.15)
				)
				(justify left bottom)
				(hide yes)
			)
		)
		(property "Footprint" "antmicro-footprints:R_0402_1005Metric"
			(at 276.86 205.74 0)
			(effects
				(font
					(size 1.27 1.27)
					(thickness 0.15)
				)
				(justify left bottom)
				(hide yes)
			)
		)
		(property "Datasheet" "https://www.bourns.com/docs/product-datasheets/cr.pdf"
			(at 279.4 205.74 0)
			(effects
				(font
					(size 1.27 1.27)
					(thickness 0.15)
				)
				(justify left bottom)
				(hide yes)
			)
		)
		(property "Description" "SMD Chip Resistor, 1 kohm, ± 1%, 63 mW, 0402 [1005 Metric], Thick Film, General Purpose"
			(at 261.62 226.06 0)
			(effects
				(font
					(size 1.27 1.27)
				)
				(hide yes)
			)
		)
		(property "MPN" "CR0402-FX-1001GLF"
			(at 281.94 205.74 0)
			(effects
				(font
					(size 1.27 1.27)
					(thickness 0.15)
				)
				(justify left bottom)
				(hide yes)
			)
		)
		(property "Manufacturer" "Bourns"
			(at 284.48 205.74 0)
			(effects
				(font
					(size 1.27 1.27)
					(thickness 0.15)
				)
				(justify left bottom)
				(hide yes)
			)
		)
		(property "License" "Apache-2.0"
			(at 287.02 205.74 0)
			(effects
				(font
					(size 1.27 1.27)
					(thickness 0.15)
				)
				(justify left bottom)
				(hide yes)
			)
		)
		(property "Author" "Antmicro"
			(at 289.56 205.74 0)
			(effects
				(font
					(size 1.27 1.27)
					(thickness 0.15)
				)
				(justify left bottom)
				(hide yes)
			)
		)
		(property "Val" "1k"
			(at 263.144 224.79 90)
			(effects
				(font
					(size 1.27 1.27)
					(thickness 0.15)
				)
				(justify right)
			)
		)
		(property "Tolerance" "1%"
			(at 271.78 205.74 0)
			(effects
				(font
					(size 1.27 1.27)
				)
				(justify left bottom)
				(hide yes)
			)
		)
		(pin "2"
		)
		(pin "1"
		)
		(instances
			(project "OCuLink to 10GbE adapter"
				(path ""
					(reference "R73")
					(unit 1)
				)
			)
		)
	)
	(symbol
		(lib_id "antmicropower:GND")
		(at 91.44 182.88 0)
		(mirror y)
		(unit 1)
		(exclude_from_sim no)
		(in_bom yes)
		(on_board yes)
		(dnp no)
		(property "Reference" "#PWR0314"
			(at 82.55 185.42 0)
			(effects
				(font
					(size 1.27 1.27)
					(thickness 0.15)
				)
				(justify left bottom)
				(hide yes)
			)
		)
		(property "Value" "GND"
			(at 91.44 186.69 0)
			(effects
				(font
					(size 1.27 1.27)
					(thickness 0.15)
				)
			)
		)
		(property "Footprint" ""
			(at 82.55 190.5 0)
			(effects
				(font
					(size 1.27 1.27)
					(thickness 0.15)
				)
				(justify left bottom)
				(hide yes)
			)
		)
		(property "Datasheet" ""
			(at 82.55 195.58 0)
			(effects
				(font
					(size 1.27 1.27)
					(thickness 0.15)
				)
				(justify left bottom)
				(hide yes)
			)
		)
		(property "Description" ""
			(at 91.44 182.88 0)
			(effects
				(font
					(size 1.27 1.27)
				)
				(hide yes)
			)
		)
		(property "Author" "Antmicro"
			(at 82.55 190.5 0)
			(effects
				(font
					(size 1.27 1.27)
					(thickness 0.15)
				)
				(justify left bottom)
				(hide yes)
			)
		)
		(property "License" "Apache-2.0"
			(at 82.55 193.04 0)
			(effects
				(font
					(size 1.27 1.27)
					(thickness 0.15)
				)
				(justify left bottom)
				(hide yes)
			)
		)
		(pin "1"
		)
		(instances
			(project "oculink-to-10gbe-adapter"
				(path ""
					(reference "#PWR0314")
					(unit 1)
				)
			)
		)
	)
)
